FILE_TYPE = MACRO_DRAWING;
SET COLOR_WIRE YELLOW;
SET COLOR_PROP ORANGE;
SET COLOR_DOT WHITE;
SET COLOR_ARC YELLOW;
SET COLOR_BODY GREEN;
SET COLOR_NOTE PURPLE;
SET PROP_DISPLAY VALUE;
SET PAGE_NUMBER P148;
FORCEADD OFFPAGE..1
(2500 2775);
FORCEPROP 2 LAST $XR0 177 
J 0
(2248 2775);
DISPLAY 0.638298 (2248 2775);
PAINT MONO (2248 2775);
FORCEPROP 2 LAST PATH I1
J 0
(2550 2850);
DISPLAY 1.021277 (2550 2850);
DISPLAY INVISIBLE (2550 2850);
FORCEPROP 1 LAST OFFPAGE TRUE
J 0
(2825 2650);
DISPLAY 0.872340 (2825 2650);
PAINT AQUA (2825 2650);
DISPLAY INVISIBLE (2825 2650);
FORCEPROP 1 LAST COMMENT_BODY TRUE
J 0
(2625 2675);
DISPLAY 0.872340 (2625 2675);
PAINT GREEN (2625 2675);
DISPLAY INVISIBLE (2625 2675);
FORCEPROP 2 LAST CDS_LIB standard
J 0
(2500 2775);
DISPLAY INVISIBLE (2500 2775);
FORCEADD OFFPAGE..1
(2500 1925);
FORCEPROP 2 LAST $XR0 177 
J 0
(2248 1925);
DISPLAY 0.638298 (2248 1925);
PAINT MONO (2248 1925);
FORCEPROP 2 LAST PATH I10
J 0
(2550 2000);
DISPLAY 1.021277 (2550 2000);
DISPLAY INVISIBLE (2550 2000);
FORCEPROP 1 LAST OFFPAGE TRUE
J 0
(2825 1800);
DISPLAY 0.872340 (2825 1800);
PAINT AQUA (2825 1800);
DISPLAY INVISIBLE (2825 1800);
FORCEPROP 1 LAST COMMENT_BODY TRUE
J 0
(2625 1825);
DISPLAY 0.872340 (2625 1825);
PAINT GREEN (2625 1825);
DISPLAY INVISIBLE (2625 1825);
FORCEPROP 2 LAST CDS_LIB standard
J 0
(2500 1925);
DISPLAY INVISIBLE (2500 1925);
FORCEADD OFFPAGE..5
(-2225 1025);
FORCEPROP 2 LAST $XR0 148 
J 0
(-2480 1025);
DISPLAY 0.638298 (-2480 1025);
PAINT MONO (-2480 1025);
FORCEPROP 2 LAST PATH I106
J 0
(-2500 1075);
DISPLAY 1.021277 (-2500 1075);
DISPLAY INVISIBLE (-2500 1075);
FORCEPROP 2 LAST CDS_LIB standard
J 0
(-2225 1025);
DISPLAY INVISIBLE (-2225 1025);
FORCEPROP 1 LAST OFFPAGE TRUE
J 0
(-1900 900);
DISPLAY 0.872340 (-1900 900);
PAINT AQUA (-1900 900);
DISPLAY INVISIBLE (-1900 900);
FORCEPROP 1 LAST COMMENT_BODY TRUE
J 0
(-2125 950);
DISPLAY 1.170213 (-2125 950);
PAINT GREEN (-2125 950);
DISPLAY INVISIBLE (-2125 950);
FORCEADD OFFPAGE..4
R 2
(2500 2625);
FORCEPROP 2 LAST $XR0 151 
J 0
(2248 2625);
DISPLAY 0.638298 (2248 2625);
PAINT MONO (2248 2625);
FORCEPROP 2 LAST PATH I107
J 0
(2250 2675);
DISPLAY 1.021277 (2250 2675);
DISPLAY INVISIBLE (2250 2675);
FORCEPROP 1 LAST COMMENT_BODY TRUE
J 2
(2525 2525);
DISPLAY 0.872340 (2525 2525);
PAINT GREEN (2525 2525);
DISPLAY INVISIBLE (2525 2525);
FORCEPROP 1 LAST OFFPAGE TRUE
J 2
(2175 2500);
DISPLAY 0.872340 (2175 2500);
PAINT GREEN (2175 2500);
DISPLAY INVISIBLE (2175 2500);
FORCEPROP 2 LAST CDS_LIB standard
J 0
(2500 2625);
DISPLAY INVISIBLE (2500 2625);
FORCEADD OFFPAGE..1
(-2225 2475);
FORCEPROP 2 LAST $XR0 151 
J 0
(-2477 2475);
DISPLAY 0.638298 (-2477 2475);
PAINT MONO (-2477 2475);
FORCEPROP 1 LAST OFFPAGE TRUE
J 0
(-1900 2350);
DISPLAY 0.872340 (-1900 2350);
PAINT AQUA (-1900 2350);
DISPLAY INVISIBLE (-1900 2350);
FORCEPROP 1 LAST COMMENT_BODY TRUE
J 0
(-2100 2375);
DISPLAY 0.872340 (-2100 2375);
PAINT GREEN (-2100 2375);
DISPLAY INVISIBLE (-2100 2375);
FORCEPROP 2 LAST CDS_LIB standard
J 0
(-2225 2475);
DISPLAY INVISIBLE (-2225 2475);
FORCEPROP 2 LAST PATH I108
J 0
(-2475 2525);
DISPLAY 1.021277 (-2475 2525);
DISPLAY INVISIBLE (-2475 2525);
FORCEADD OFFPAGE..2
R 2
(-2225 2625);
FORCEPROP 2 LAST $XR1 227 
J 0
(-2600 2625);
DISPLAY 0.638298 (-2600 2625);
PAINT MONO (-2600 2625);
FORCEPROP 2 LAST $XR0 144 
J 0
(-2480 2625);
DISPLAY 0.638298 (-2480 2625);
PAINT MONO (-2480 2625);
FORCEPROP 1 LAST OFFPAGE TRUE
J 2
(-2550 2500);
DISPLAY 0.872340 (-2550 2500);
PAINT AQUA (-2550 2500);
DISPLAY INVISIBLE (-2550 2500);
FORCEPROP 1 LAST COMMENT_BODY TRUE
J 2
(-2180 2530);
DISPLAY 0.872340 (-2180 2530);
PAINT GREEN (-2180 2530);
DISPLAY INVISIBLE (-2180 2530);
FORCEPROP 2 LAST CDS_LIB standard
J 0
(-2225 2625);
DISPLAY INVISIBLE (-2225 2625);
FORCEPROP 2 LAST PATH I109
J 0
(-2500 2675);
DISPLAY 1.021277 (-2500 2675);
DISPLAY INVISIBLE (-2500 2675);
FORCEADD OFFPAGE..1
(2500 2025);
FORCEPROP 2 LAST $XR0 176 
J 0
(2248 2025);
DISPLAY 0.638298 (2248 2025);
PAINT MONO (2248 2025);
FORCEPROP 2 LAST CDS_LIB standard
J 0
(2500 2025);
DISPLAY INVISIBLE (2500 2025);
FORCEPROP 1 LAST COMMENT_BODY TRUE
J 0
(2625 1925);
DISPLAY 0.872340 (2625 1925);
PAINT GREEN (2625 1925);
DISPLAY INVISIBLE (2625 1925);
FORCEPROP 1 LAST OFFPAGE TRUE
J 0
(2825 1900);
DISPLAY 0.872340 (2825 1900);
PAINT AQUA (2825 1900);
DISPLAY INVISIBLE (2825 1900);
FORCEPROP 2 LAST PATH I11
J 0
(2550 2100);
DISPLAY 1.021277 (2550 2100);
DISPLAY INVISIBLE (2550 2100);
FORCEADD OFFPAGE..2
R 2
(2500 2475);
FORCEPROP 2 LAST $XR1 227 
J 0
(2125 2475);
DISPLAY 0.638298 (2125 2475);
PAINT MONO (2125 2475);
FORCEPROP 2 LAST $XR0 144 
J 0
(2245 2475);
DISPLAY 0.638298 (2245 2475);
PAINT MONO (2245 2475);
FORCEPROP 2 LAST CDS_LIB standard
J 0
(2500 2475);
DISPLAY INVISIBLE (2500 2475);
FORCEPROP 1 LAST COMMENT_BODY TRUE
J 2
(2545 2380);
DISPLAY 0.872340 (2545 2380);
PAINT GREEN (2545 2380);
DISPLAY INVISIBLE (2545 2380);
FORCEPROP 1 LAST OFFPAGE TRUE
J 2
(2175 2350);
DISPLAY 0.872340 (2175 2350);
PAINT AQUA (2175 2350);
DISPLAY INVISIBLE (2175 2350);
FORCEPROP 2 LAST PATH I114
J 0
(2225 2525);
DISPLAY 1.021277 (2225 2525);
DISPLAY INVISIBLE (2225 2525);
FORCEADD OFFPAGE..2
R 2
(-2250 875);
FORCEPROP 2 LAST $XR1 227 
J 0
(-2625 875);
DISPLAY 0.638298 (-2625 875);
PAINT MONO (-2625 875);
FORCEPROP 2 LAST $XR0 144 
J 0
(-2505 875);
DISPLAY 0.638298 (-2505 875);
PAINT MONO (-2505 875);
FORCEPROP 2 LAST PATH I118
J 0
(-2525 925);
DISPLAY 1.021277 (-2525 925);
DISPLAY INVISIBLE (-2525 925);
FORCEPROP 1 LAST OFFPAGE TRUE
J 2
(-2575 750);
DISPLAY 0.872340 (-2575 750);
PAINT AQUA (-2575 750);
DISPLAY INVISIBLE (-2575 750);
FORCEPROP 1 LAST COMMENT_BODY TRUE
J 2
(-2205 780);
DISPLAY 0.872340 (-2205 780);
PAINT GREEN (-2205 780);
DISPLAY INVISIBLE (-2205 780);
FORCEPROP 2 LAST CDS_LIB standard
J 0
(-2250 875);
DISPLAY INVISIBLE (-2250 875);
FORCEADD OFFPAGE..5
(2500 2175);
FORCEPROP 2 LAST $XR0 62 
J 0
(2276 2175);
DISPLAY 0.638298 (2276 2175);
PAINT MONO (2276 2175);
FORCEPROP 2 LAST PATH I12
J 0
(2550 2250);
DISPLAY 1.021277 (2550 2250);
DISPLAY INVISIBLE (2550 2250);
FORCEPROP 1 LAST OFFPAGE TRUE
J 0
(2825 2050);
DISPLAY 0.872340 (2825 2050);
PAINT AQUA (2825 2050);
DISPLAY INVISIBLE (2825 2050);
FORCEPROP 1 LAST COMMENT_BODY TRUE
J 0
(2600 2100);
DISPLAY 1.170213 (2600 2100);
PAINT GREEN (2600 2100);
DISPLAY INVISIBLE (2600 2100);
FORCEPROP 2 LAST CDS_LIB standard
J 0
(2500 2175);
DISPLAY INVISIBLE (2500 2175);
FORCEADD OFFPAGE..2
R 2
(2475 875);
FORCEPROP 2 LAST $XR1 227 
J 0
(2100 875);
DISPLAY 0.638298 (2100 875);
PAINT MONO (2100 875);
FORCEPROP 2 LAST $XR0 144 
J 0
(2220 875);
DISPLAY 0.638298 (2220 875);
PAINT MONO (2220 875);
FORCEPROP 2 LAST CDS_LIB standard
J 0
(2475 875);
DISPLAY INVISIBLE (2475 875);
FORCEPROP 1 LAST COMMENT_BODY TRUE
J 2
(2520 780);
DISPLAY 0.872340 (2520 780);
PAINT GREEN (2520 780);
DISPLAY INVISIBLE (2520 780);
FORCEPROP 1 LAST OFFPAGE TRUE
J 2
(2150 750);
DISPLAY 0.872340 (2150 750);
PAINT AQUA (2150 750);
DISPLAY INVISIBLE (2150 750);
FORCEPROP 2 LAST PATH I120
J 0
(2200 925);
DISPLAY 1.021277 (2200 925);
DISPLAY INVISIBLE (2200 925);
FORCEADD OFFPAGE..5
(2500 1025);
FORCEPROP 2 LAST $XR0 147 
J 0
(2245 1025);
DISPLAY 0.638298 (2245 1025);
PAINT MONO (2245 1025);
FORCEPROP 1 LAST OFFPAGE TRUE
J 0
(2825 900);
DISPLAY 0.872340 (2825 900);
PAINT AQUA (2825 900);
DISPLAY INVISIBLE (2825 900);
FORCEPROP 1 LAST COMMENT_BODY TRUE
J 0
(2600 950);
DISPLAY 1.170213 (2600 950);
PAINT GREEN (2600 950);
DISPLAY INVISIBLE (2600 950);
FORCEPROP 2 LAST PATH I121
J 0
(2550 1100);
DISPLAY 1.021277 (2550 1100);
DISPLAY INVISIBLE (2550 1100);
FORCEPROP 2 LAST CDS_LIB standard
J 0
(2500 1025);
DISPLAY INVISIBLE (2500 1025);
FORCEADD OFFPAGE..1
(2500 2075);
FORCEPROP 2 LAST $XR0 176 
J 0
(2248 2075);
DISPLAY 0.638298 (2248 2075);
PAINT MONO (2248 2075);
FORCEPROP 1 LAST OFFPAGE TRUE
J 0
(2825 1950);
DISPLAY 0.872340 (2825 1950);
PAINT AQUA (2825 1950);
DISPLAY INVISIBLE (2825 1950);
FORCEPROP 1 LAST COMMENT_BODY TRUE
J 0
(2625 1975);
DISPLAY 0.872340 (2625 1975);
PAINT GREEN (2625 1975);
DISPLAY INVISIBLE (2625 1975);
FORCEPROP 2 LAST CDS_LIB standard
J 0
(2500 2075);
DISPLAY INVISIBLE (2500 2075);
FORCEPROP 2 LAST PATH I13
J 0
(2550 2150);
DISPLAY 1.021277 (2550 2150);
DISPLAY INVISIBLE (2550 2150);
FORCEADD OFFPAGE..2
R 2
(2500 2225);
FORCEPROP 2 LAST $XR0 62 
J 0
(2276 2225);
DISPLAY 0.638298 (2276 2225);
PAINT MONO (2276 2225);
FORCEPROP 2 LAST PATH I14
J 0
(2550 2300);
DISPLAY 1.021277 (2550 2300);
DISPLAY INVISIBLE (2550 2300);
FORCEPROP 1 LAST OFFPAGE TRUE
J 2
(2175 2100);
DISPLAY 0.872340 (2175 2100);
PAINT AQUA (2175 2100);
DISPLAY INVISIBLE (2175 2100);
FORCEPROP 1 LAST COMMENT_BODY TRUE
J 2
(2545 2130);
DISPLAY 0.872340 (2545 2130);
PAINT GREEN (2545 2130);
DISPLAY INVISIBLE (2545 2130);
FORCEPROP 2 LAST CDS_LIB standard
J 0
(2500 2225);
DISPLAY INVISIBLE (2500 2225);
FORCEADD OFFPAGE..5
(2500 2325);
FORCEPROP 2 LAST $XR0 60 
J 0
(2276 2325);
DISPLAY 0.638298 (2276 2325);
PAINT MONO (2276 2325);
FORCEPROP 2 LAST PATH I15
J 0
(2550 2400);
DISPLAY 1.021277 (2550 2400);
DISPLAY INVISIBLE (2550 2400);
FORCEPROP 1 LAST OFFPAGE TRUE
J 0
(2825 2200);
DISPLAY 0.872340 (2825 2200);
PAINT AQUA (2825 2200);
DISPLAY INVISIBLE (2825 2200);
FORCEPROP 1 LAST COMMENT_BODY TRUE
J 0
(2600 2250);
DISPLAY 1.170213 (2600 2250);
PAINT GREEN (2600 2250);
DISPLAY INVISIBLE (2600 2250);
FORCEPROP 2 LAST CDS_LIB standard
J 0
(2500 2325);
DISPLAY INVISIBLE (2500 2325);
FORCEADD OFFPAGE..2
R 2
(2500 2375);
FORCEPROP 2 LAST $XR0 60 
J 0
(2276 2375);
DISPLAY 0.638298 (2276 2375);
PAINT MONO (2276 2375);
FORCEPROP 2 LAST PATH I16
J 0
(2550 2450);
DISPLAY 1.021277 (2550 2450);
DISPLAY INVISIBLE (2550 2450);
FORCEPROP 1 LAST OFFPAGE TRUE
J 2
(2175 2250);
DISPLAY 0.872340 (2175 2250);
PAINT AQUA (2175 2250);
DISPLAY INVISIBLE (2175 2250);
FORCEPROP 1 LAST COMMENT_BODY TRUE
J 2
(2545 2280);
DISPLAY 0.872340 (2545 2280);
PAINT GREEN (2545 2280);
DISPLAY INVISIBLE (2545 2280);
FORCEPROP 2 LAST CDS_LIB standard
J 0
(2500 2375);
DISPLAY INVISIBLE (2500 2375);
FORCEADD OFFPAGE..1
(2500 2725);
FORCEPROP 2 LAST $XR0 177 
J 0
(2248 2725);
DISPLAY 0.638298 (2248 2725);
PAINT MONO (2248 2725);
FORCEPROP 2 LAST PATH I2
J 0
(2550 2800);
DISPLAY 1.021277 (2550 2800);
DISPLAY INVISIBLE (2550 2800);
FORCEPROP 2 LAST CDS_LIB standard
J 0
(2500 2725);
DISPLAY INVISIBLE (2500 2725);
FORCEPROP 1 LAST COMMENT_BODY TRUE
J 0
(2625 2625);
DISPLAY 0.872340 (2625 2625);
PAINT GREEN (2625 2625);
DISPLAY INVISIBLE (2625 2625);
FORCEPROP 1 LAST OFFPAGE TRUE
J 0
(2825 2600);
DISPLAY 0.872340 (2825 2600);
PAINT AQUA (2825 2600);
DISPLAY INVISIBLE (2825 2600);
FORCEADD OFFPAGE..1
(2500 2875);
FORCEPROP 2 LAST $XR0 176 
J 0
(2248 2875);
DISPLAY 0.638298 (2248 2875);
PAINT MONO (2248 2875);
FORCEPROP 1 LAST OFFPAGE TRUE
J 0
(2825 2750);
DISPLAY 0.872340 (2825 2750);
PAINT AQUA (2825 2750);
DISPLAY INVISIBLE (2825 2750);
FORCEPROP 1 LAST COMMENT_BODY TRUE
J 0
(2625 2775);
DISPLAY 0.872340 (2625 2775);
PAINT GREEN (2625 2775);
DISPLAY INVISIBLE (2625 2775);
FORCEPROP 2 LAST CDS_LIB standard
J 0
(2500 2875);
DISPLAY INVISIBLE (2500 2875);
FORCEPROP 2 LAST PATH I3
J 0
(2550 2950);
DISPLAY 1.021277 (2550 2950);
DISPLAY INVISIBLE (2550 2950);
FORCEADD OFFPAGE..1
(-2225 2875);
FORCEPROP 2 LAST $XR0 176 
J 0
(-2477 2875);
DISPLAY 0.638298 (-2477 2875);
PAINT MONO (-2477 2875);
FORCEPROP 2 LAST CDS_LIB standard
J 0
(-2225 2875);
DISPLAY INVISIBLE (-2225 2875);
FORCEPROP 1 LAST COMMENT_BODY TRUE
J 0
(-2100 2775);
DISPLAY 0.872340 (-2100 2775);
PAINT GREEN (-2100 2775);
DISPLAY INVISIBLE (-2100 2775);
FORCEPROP 1 LAST OFFPAGE TRUE
J 0
(-1900 2750);
DISPLAY 0.872340 (-1900 2750);
PAINT AQUA (-1900 2750);
DISPLAY INVISIBLE (-1900 2750);
FORCEPROP 2 LAST PATH I34
J 0
(-2175 2950);
DISPLAY 1.021277 (-2175 2950);
DISPLAY INVISIBLE (-2175 2950);
FORCEADD OFFPAGE..1
(-2225 2725);
FORCEPROP 2 LAST $XR0 177 
J 0
(-2477 2725);
DISPLAY 0.638298 (-2477 2725);
PAINT MONO (-2477 2725);
FORCEPROP 2 LAST PATH I35
J 0
(-2175 2800);
DISPLAY 1.021277 (-2175 2800);
DISPLAY INVISIBLE (-2175 2800);
FORCEPROP 2 LAST CDS_LIB standard
J 0
(-2225 2725);
DISPLAY INVISIBLE (-2225 2725);
FORCEPROP 1 LAST COMMENT_BODY TRUE
J 0
(-2100 2625);
DISPLAY 0.872340 (-2100 2625);
PAINT GREEN (-2100 2625);
DISPLAY INVISIBLE (-2100 2625);
FORCEPROP 1 LAST OFFPAGE TRUE
J 0
(-1900 2600);
DISPLAY 0.872340 (-1900 2600);
PAINT AQUA (-1900 2600);
DISPLAY INVISIBLE (-1900 2600);
FORCEADD OFFPAGE..1
(-2225 2775);
FORCEPROP 2 LAST $XR0 177 
J 0
(-2477 2775);
DISPLAY 0.638298 (-2477 2775);
PAINT MONO (-2477 2775);
FORCEPROP 2 LAST PATH I36
J 0
(-2175 2850);
DISPLAY 1.021277 (-2175 2850);
DISPLAY INVISIBLE (-2175 2850);
FORCEPROP 1 LAST OFFPAGE TRUE
J 0
(-1900 2650);
DISPLAY 0.872340 (-1900 2650);
PAINT AQUA (-1900 2650);
DISPLAY INVISIBLE (-1900 2650);
FORCEPROP 1 LAST COMMENT_BODY TRUE
J 0
(-2100 2675);
DISPLAY 0.872340 (-2100 2675);
PAINT GREEN (-2100 2675);
DISPLAY INVISIBLE (-2100 2675);
FORCEPROP 2 LAST CDS_LIB standard
J 0
(-2225 2775);
DISPLAY INVISIBLE (-2225 2775);
FORCEADD OFFPAGE..1
(-2225 2925);
FORCEPROP 2 LAST $XR0 176 
J 0
(-2477 2925);
DISPLAY 0.638298 (-2477 2925);
PAINT MONO (-2477 2925);
FORCEPROP 1 LAST OFFPAGE TRUE
J 0
(-1900 2800);
DISPLAY 0.872340 (-1900 2800);
PAINT AQUA (-1900 2800);
DISPLAY INVISIBLE (-1900 2800);
FORCEPROP 1 LAST COMMENT_BODY TRUE
J 0
(-2100 2825);
DISPLAY 0.872340 (-2100 2825);
PAINT GREEN (-2100 2825);
DISPLAY INVISIBLE (-2100 2825);
FORCEPROP 2 LAST CDS_LIB standard
J 0
(-2225 2925);
DISPLAY INVISIBLE (-2225 2925);
FORCEPROP 2 LAST PATH I37
J 0
(-2175 3000);
DISPLAY 1.021277 (-2175 3000);
DISPLAY INVISIBLE (-2175 3000);
FORCEADD OFFPAGE..2
R 2
(-2225 3075);
FORCEPROP 2 LAST $XR0 62 
J 0
(-2449 3075);
DISPLAY 0.638298 (-2449 3075);
PAINT MONO (-2449 3075);
FORCEPROP 1 LAST OFFPAGE TRUE
J 2
(-2550 2950);
DISPLAY 0.872340 (-2550 2950);
PAINT AQUA (-2550 2950);
DISPLAY INVISIBLE (-2550 2950);
FORCEPROP 1 LAST COMMENT_BODY TRUE
J 2
(-2180 2980);
DISPLAY 0.872340 (-2180 2980);
PAINT GREEN (-2180 2980);
DISPLAY INVISIBLE (-2180 2980);
FORCEPROP 2 LAST CDS_LIB standard
J 0
(-2225 3075);
DISPLAY INVISIBLE (-2225 3075);
FORCEPROP 2 LAST PATH I38
J 0
(-2175 3150);
DISPLAY 1.021277 (-2175 3150);
DISPLAY INVISIBLE (-2175 3150);
FORCEADD OFFPAGE..5
(-2225 3025);
FORCEPROP 2 LAST $XR0 62 
J 0
(-2449 3025);
DISPLAY 0.638298 (-2449 3025);
PAINT MONO (-2449 3025);
FORCEPROP 1 LAST OFFPAGE TRUE
J 0
(-1900 2900);
DISPLAY 0.872340 (-1900 2900);
PAINT AQUA (-1900 2900);
DISPLAY INVISIBLE (-1900 2900);
FORCEPROP 1 LAST COMMENT_BODY TRUE
J 0
(-2125 2950);
DISPLAY 1.170213 (-2125 2950);
PAINT GREEN (-2125 2950);
DISPLAY INVISIBLE (-2125 2950);
FORCEPROP 2 LAST CDS_LIB standard
J 0
(-2225 3025);
DISPLAY INVISIBLE (-2225 3025);
FORCEPROP 2 LAST PATH I39
J 0
(-2175 3100);
DISPLAY 1.021277 (-2175 3100);
DISPLAY INVISIBLE (-2175 3100);
FORCEADD OFFPAGE..5
(2500 3025);
FORCEPROP 2 LAST $XR0 62 
J 0
(2276 3025);
DISPLAY 0.638298 (2276 3025);
PAINT MONO (2276 3025);
FORCEPROP 2 LAST CDS_LIB standard
J 0
(2500 3025);
DISPLAY INVISIBLE (2500 3025);
FORCEPROP 1 LAST COMMENT_BODY TRUE
J 0
(2600 2950);
DISPLAY 1.170213 (2600 2950);
PAINT GREEN (2600 2950);
DISPLAY INVISIBLE (2600 2950);
FORCEPROP 1 LAST OFFPAGE TRUE
J 0
(2825 2900);
DISPLAY 0.872340 (2825 2900);
PAINT AQUA (2825 2900);
DISPLAY INVISIBLE (2825 2900);
FORCEPROP 2 LAST PATH I4
J 0
(2550 3100);
DISPLAY 1.021277 (2550 3100);
DISPLAY INVISIBLE (2550 3100);
FORCEADD OFFPAGE..5
(-2225 3175);
FORCEPROP 2 LAST $XR0 60 
J 0
(-2449 3175);
DISPLAY 0.638298 (-2449 3175);
PAINT MONO (-2449 3175);
FORCEPROP 2 LAST CDS_LIB standard
J 0
(-2225 3175);
DISPLAY INVISIBLE (-2225 3175);
FORCEPROP 1 LAST COMMENT_BODY TRUE
J 0
(-2125 3100);
DISPLAY 1.170213 (-2125 3100);
PAINT GREEN (-2125 3100);
DISPLAY INVISIBLE (-2125 3100);
FORCEPROP 1 LAST OFFPAGE TRUE
J 0
(-1900 3050);
DISPLAY 0.872340 (-1900 3050);
PAINT AQUA (-1900 3050);
DISPLAY INVISIBLE (-1900 3050);
FORCEPROP 2 LAST PATH I40
J 0
(-2175 3250);
DISPLAY 1.021277 (-2175 3250);
DISPLAY INVISIBLE (-2175 3250);
FORCEADD OFFPAGE..1
(-2225 1925);
FORCEPROP 2 LAST $XR0 177 
J 0
(-2477 1925);
DISPLAY 0.638298 (-2477 1925);
PAINT MONO (-2477 1925);
FORCEPROP 2 LAST PATH I42
J 0
(-2175 2000);
DISPLAY 1.021277 (-2175 2000);
DISPLAY INVISIBLE (-2175 2000);
FORCEPROP 1 LAST OFFPAGE TRUE
J 0
(-1900 1800);
DISPLAY 0.872340 (-1900 1800);
PAINT AQUA (-1900 1800);
DISPLAY INVISIBLE (-1900 1800);
FORCEPROP 1 LAST COMMENT_BODY TRUE
J 0
(-2100 1825);
DISPLAY 0.872340 (-2100 1825);
PAINT GREEN (-2100 1825);
DISPLAY INVISIBLE (-2100 1825);
FORCEPROP 2 LAST CDS_LIB standard
J 0
(-2225 1925);
DISPLAY INVISIBLE (-2225 1925);
FORCEADD OFFPAGE..1
(-2225 1875);
FORCEPROP 2 LAST $XR0 177 
J 0
(-2477 1875);
DISPLAY 0.638298 (-2477 1875);
PAINT MONO (-2477 1875);
FORCEPROP 2 LAST PATH I43
J 0
(-2175 1950);
DISPLAY 1.021277 (-2175 1950);
DISPLAY INVISIBLE (-2175 1950);
FORCEPROP 2 LAST CDS_LIB standard
J 0
(-2225 1875);
DISPLAY INVISIBLE (-2225 1875);
FORCEPROP 1 LAST COMMENT_BODY TRUE
J 0
(-2100 1775);
DISPLAY 0.872340 (-2100 1775);
PAINT GREEN (-2100 1775);
DISPLAY INVISIBLE (-2100 1775);
FORCEPROP 1 LAST OFFPAGE TRUE
J 0
(-1900 1750);
DISPLAY 0.872340 (-1900 1750);
PAINT AQUA (-1900 1750);
DISPLAY INVISIBLE (-1900 1750);
FORCEADD OFFPAGE..1
(-2225 2025);
FORCEPROP 2 LAST $XR0 176 
J 0
(-2477 2025);
DISPLAY 0.638298 (-2477 2025);
PAINT MONO (-2477 2025);
FORCEPROP 2 LAST CDS_LIB standard
J 0
(-2225 2025);
DISPLAY INVISIBLE (-2225 2025);
FORCEPROP 1 LAST COMMENT_BODY TRUE
J 0
(-2100 1925);
DISPLAY 0.872340 (-2100 1925);
PAINT GREEN (-2100 1925);
DISPLAY INVISIBLE (-2100 1925);
FORCEPROP 1 LAST OFFPAGE TRUE
J 0
(-1900 1900);
DISPLAY 0.872340 (-1900 1900);
PAINT AQUA (-1900 1900);
DISPLAY INVISIBLE (-1900 1900);
FORCEPROP 2 LAST PATH I44
J 0
(-2175 2100);
DISPLAY 1.021277 (-2175 2100);
DISPLAY INVISIBLE (-2175 2100);
FORCEADD OFFPAGE..1
(-2225 2075);
FORCEPROP 2 LAST $XR0 176 
J 0
(-2477 2075);
DISPLAY 0.638298 (-2477 2075);
PAINT MONO (-2477 2075);
FORCEPROP 1 LAST OFFPAGE TRUE
J 0
(-1900 1950);
DISPLAY 0.872340 (-1900 1950);
PAINT AQUA (-1900 1950);
DISPLAY INVISIBLE (-1900 1950);
FORCEPROP 1 LAST COMMENT_BODY TRUE
J 0
(-2100 1975);
DISPLAY 0.872340 (-2100 1975);
PAINT GREEN (-2100 1975);
DISPLAY INVISIBLE (-2100 1975);
FORCEPROP 2 LAST CDS_LIB standard
J 0
(-2225 2075);
DISPLAY INVISIBLE (-2225 2075);
FORCEPROP 2 LAST PATH I45
J 0
(-2175 2150);
DISPLAY 1.021277 (-2175 2150);
DISPLAY INVISIBLE (-2175 2150);
FORCEADD OFFPAGE..2
R 2
(-2225 2375);
FORCEPROP 2 LAST $XR0 60 
J 0
(-2449 2375);
DISPLAY 0.638298 (-2449 2375);
PAINT MONO (-2449 2375);
FORCEPROP 2 LAST PATH I46
J 0
(-2175 2450);
DISPLAY 1.021277 (-2175 2450);
DISPLAY INVISIBLE (-2175 2450);
FORCEPROP 2 LAST CDS_LIB standard
J 0
(-2225 2375);
DISPLAY INVISIBLE (-2225 2375);
FORCEPROP 1 LAST COMMENT_BODY TRUE
J 2
(-2180 2280);
DISPLAY 0.872340 (-2180 2280);
PAINT GREEN (-2180 2280);
DISPLAY INVISIBLE (-2180 2280);
FORCEPROP 1 LAST OFFPAGE TRUE
J 2
(-2550 2250);
DISPLAY 0.872340 (-2550 2250);
PAINT AQUA (-2550 2250);
DISPLAY INVISIBLE (-2550 2250);
FORCEADD OFFPAGE..5
(-2225 2325);
FORCEPROP 2 LAST $XR0 60 
J 0
(-2449 2325);
DISPLAY 0.638298 (-2449 2325);
PAINT MONO (-2449 2325);
FORCEPROP 2 LAST PATH I47
J 0
(-2175 2400);
DISPLAY 1.021277 (-2175 2400);
DISPLAY INVISIBLE (-2175 2400);
FORCEPROP 2 LAST CDS_LIB standard
J 0
(-2225 2325);
DISPLAY INVISIBLE (-2225 2325);
FORCEPROP 1 LAST COMMENT_BODY TRUE
J 0
(-2125 2250);
DISPLAY 1.170213 (-2125 2250);
PAINT GREEN (-2125 2250);
DISPLAY INVISIBLE (-2125 2250);
FORCEPROP 1 LAST OFFPAGE TRUE
J 0
(-1900 2200);
DISPLAY 0.872340 (-1900 2200);
PAINT AQUA (-1900 2200);
DISPLAY INVISIBLE (-1900 2200);
FORCEADD OFFPAGE..2
R 2
(-2225 2225);
FORCEPROP 2 LAST $XR0 62 
J 0
(-2449 2225);
DISPLAY 0.638298 (-2449 2225);
PAINT MONO (-2449 2225);
FORCEPROP 2 LAST CDS_LIB standard
J 0
(-2225 2225);
DISPLAY INVISIBLE (-2225 2225);
FORCEPROP 1 LAST COMMENT_BODY TRUE
J 2
(-2180 2130);
DISPLAY 0.872340 (-2180 2130);
PAINT GREEN (-2180 2130);
DISPLAY INVISIBLE (-2180 2130);
FORCEPROP 1 LAST OFFPAGE TRUE
J 2
(-2550 2100);
DISPLAY 0.872340 (-2550 2100);
PAINT AQUA (-2550 2100);
DISPLAY INVISIBLE (-2550 2100);
FORCEPROP 2 LAST PATH I48
J 0
(-2175 2300);
DISPLAY 1.021277 (-2175 2300);
DISPLAY INVISIBLE (-2175 2300);
FORCEADD OFFPAGE..5
(-2225 2175);
FORCEPROP 2 LAST $XR0 62 
J 0
(-2449 2175);
DISPLAY 0.638298 (-2449 2175);
PAINT MONO (-2449 2175);
FORCEPROP 2 LAST CDS_LIB standard
J 0
(-2225 2175);
DISPLAY INVISIBLE (-2225 2175);
FORCEPROP 1 LAST COMMENT_BODY TRUE
J 0
(-2125 2100);
DISPLAY 1.170213 (-2125 2100);
PAINT GREEN (-2125 2100);
DISPLAY INVISIBLE (-2125 2100);
FORCEPROP 1 LAST OFFPAGE TRUE
J 0
(-1900 2050);
DISPLAY 0.872340 (-1900 2050);
PAINT AQUA (-1900 2050);
DISPLAY INVISIBLE (-1900 2050);
FORCEPROP 2 LAST PATH I49
J 0
(-2175 2250);
DISPLAY 1.021277 (-2175 2250);
DISPLAY INVISIBLE (-2175 2250);
FORCEADD OFFPAGE..1
(2500 2925);
FORCEPROP 2 LAST $XR0 176 
J 0
(2248 2925);
DISPLAY 0.638298 (2248 2925);
PAINT MONO (2248 2925);
FORCEPROP 2 LAST CDS_LIB standard
J 0
(2500 2925);
DISPLAY INVISIBLE (2500 2925);
FORCEPROP 1 LAST COMMENT_BODY TRUE
J 0
(2625 2825);
DISPLAY 0.872340 (2625 2825);
PAINT GREEN (2625 2825);
DISPLAY INVISIBLE (2625 2825);
FORCEPROP 1 LAST OFFPAGE TRUE
J 0
(2825 2800);
DISPLAY 0.872340 (2825 2800);
PAINT AQUA (2825 2800);
DISPLAY INVISIBLE (2825 2800);
FORCEPROP 2 LAST PATH I5
J 0
(2550 3000);
DISPLAY 1.021277 (2550 3000);
DISPLAY INVISIBLE (2550 3000);
FORCEADD OFFPAGE..1
(-2225 1275);
FORCEPROP 2 LAST $XR0 176 
J 0
(-2477 1275);
DISPLAY 0.638298 (-2477 1275);
PAINT MONO (-2477 1275);
FORCEPROP 2 LAST CDS_LIB standard
J 0
(-2225 1275);
DISPLAY INVISIBLE (-2225 1275);
FORCEPROP 1 LAST COMMENT_BODY TRUE
J 0
(-2100 1175);
DISPLAY 0.872340 (-2100 1175);
PAINT GREEN (-2100 1175);
DISPLAY INVISIBLE (-2100 1175);
FORCEPROP 1 LAST OFFPAGE TRUE
J 0
(-1900 1150);
DISPLAY 0.872340 (-1900 1150);
PAINT AQUA (-1900 1150);
DISPLAY INVISIBLE (-1900 1150);
FORCEPROP 2 LAST PATH I50
J 0
(-2175 1350);
DISPLAY 1.021277 (-2175 1350);
DISPLAY INVISIBLE (-2175 1350);
FORCEADD OFFPAGE..1
(-2225 1175);
FORCEPROP 2 LAST $XR0 177 
J 0
(-2477 1175);
DISPLAY 0.638298 (-2477 1175);
PAINT MONO (-2477 1175);
FORCEPROP 1 LAST OFFPAGE TRUE
J 0
(-1900 1050);
DISPLAY 0.872340 (-1900 1050);
PAINT AQUA (-1900 1050);
DISPLAY INVISIBLE (-1900 1050);
FORCEPROP 1 LAST COMMENT_BODY TRUE
J 0
(-2100 1075);
DISPLAY 0.872340 (-2100 1075);
PAINT GREEN (-2100 1075);
DISPLAY INVISIBLE (-2100 1075);
FORCEPROP 2 LAST CDS_LIB standard
J 0
(-2225 1175);
DISPLAY INVISIBLE (-2225 1175);
FORCEPROP 2 LAST PATH I51
J 0
(-2175 1250);
DISPLAY 1.021277 (-2175 1250);
DISPLAY INVISIBLE (-2175 1250);
FORCEADD OFFPAGE..1
(-2225 1125);
FORCEPROP 2 LAST $XR0 177 
J 0
(-2477 1125);
DISPLAY 0.638298 (-2477 1125);
PAINT MONO (-2477 1125);
FORCEPROP 1 LAST OFFPAGE TRUE
J 0
(-1900 1000);
DISPLAY 0.872340 (-1900 1000);
PAINT AQUA (-1900 1000);
DISPLAY INVISIBLE (-1900 1000);
FORCEPROP 1 LAST COMMENT_BODY TRUE
J 0
(-2100 1025);
DISPLAY 0.872340 (-2100 1025);
PAINT GREEN (-2100 1025);
DISPLAY INVISIBLE (-2100 1025);
FORCEPROP 2 LAST CDS_LIB standard
J 0
(-2225 1125);
DISPLAY INVISIBLE (-2225 1125);
FORCEPROP 2 LAST PATH I52
J 0
(-2175 1200);
DISPLAY 1.021277 (-2175 1200);
DISPLAY INVISIBLE (-2175 1200);
FORCEADD OFFPAGE..1
(-2225 1325);
FORCEPROP 2 LAST $XR0 176 
J 0
(-2477 1325);
DISPLAY 0.638298 (-2477 1325);
PAINT MONO (-2477 1325);
FORCEPROP 2 LAST CDS_LIB standard
J 0
(-2225 1325);
DISPLAY INVISIBLE (-2225 1325);
FORCEPROP 1 LAST COMMENT_BODY TRUE
J 0
(-2100 1225);
DISPLAY 0.872340 (-2100 1225);
PAINT GREEN (-2100 1225);
DISPLAY INVISIBLE (-2100 1225);
FORCEPROP 1 LAST OFFPAGE TRUE
J 0
(-1900 1200);
DISPLAY 0.872340 (-1900 1200);
PAINT AQUA (-1900 1200);
DISPLAY INVISIBLE (-1900 1200);
FORCEPROP 2 LAST PATH I53
J 0
(-2175 1400);
DISPLAY 1.021277 (-2175 1400);
DISPLAY INVISIBLE (-2175 1400);
FORCEADD OFFPAGE..2
R 2
(-2225 1625);
FORCEPROP 2 LAST $XR0 60 
J 0
(-2449 1625);
DISPLAY 0.638298 (-2449 1625);
PAINT MONO (-2449 1625);
FORCEPROP 2 LAST PATH I54
J 0
(-2175 1700);
DISPLAY 1.021277 (-2175 1700);
DISPLAY INVISIBLE (-2175 1700);
FORCEPROP 1 LAST OFFPAGE TRUE
J 2
(-2550 1500);
DISPLAY 0.872340 (-2550 1500);
PAINT AQUA (-2550 1500);
DISPLAY INVISIBLE (-2550 1500);
FORCEPROP 1 LAST COMMENT_BODY TRUE
J 2
(-2180 1530);
DISPLAY 0.872340 (-2180 1530);
PAINT GREEN (-2180 1530);
DISPLAY INVISIBLE (-2180 1530);
FORCEPROP 2 LAST CDS_LIB standard
J 0
(-2225 1625);
DISPLAY INVISIBLE (-2225 1625);
FORCEADD OFFPAGE..5
(-2225 1575);
FORCEPROP 2 LAST $XR0 60 
J 0
(-2449 1575);
DISPLAY 0.638298 (-2449 1575);
PAINT MONO (-2449 1575);
FORCEPROP 2 LAST PATH I55
J 0
(-2175 1650);
DISPLAY 1.021277 (-2175 1650);
DISPLAY INVISIBLE (-2175 1650);
FORCEPROP 1 LAST OFFPAGE TRUE
J 0
(-1900 1450);
DISPLAY 0.872340 (-1900 1450);
PAINT AQUA (-1900 1450);
DISPLAY INVISIBLE (-1900 1450);
FORCEPROP 1 LAST COMMENT_BODY TRUE
J 0
(-2125 1500);
DISPLAY 1.170213 (-2125 1500);
PAINT GREEN (-2125 1500);
DISPLAY INVISIBLE (-2125 1500);
FORCEPROP 2 LAST CDS_LIB standard
J 0
(-2225 1575);
DISPLAY INVISIBLE (-2225 1575);
FORCEADD OFFPAGE..5
(-2225 1425);
FORCEPROP 2 LAST $XR0 62 
J 0
(-2449 1425);
DISPLAY 0.638298 (-2449 1425);
PAINT MONO (-2449 1425);
FORCEPROP 2 LAST PATH I56
J 0
(-2175 1500);
DISPLAY 1.021277 (-2175 1500);
DISPLAY INVISIBLE (-2175 1500);
FORCEPROP 1 LAST OFFPAGE TRUE
J 0
(-1900 1300);
DISPLAY 0.872340 (-1900 1300);
PAINT AQUA (-1900 1300);
DISPLAY INVISIBLE (-1900 1300);
FORCEPROP 1 LAST COMMENT_BODY TRUE
J 0
(-2125 1350);
DISPLAY 1.170213 (-2125 1350);
PAINT GREEN (-2125 1350);
DISPLAY INVISIBLE (-2125 1350);
FORCEPROP 2 LAST CDS_LIB standard
J 0
(-2225 1425);
DISPLAY INVISIBLE (-2225 1425);
FORCEADD OFFPAGE..2
R 2
(-2225 1475);
FORCEPROP 2 LAST $XR0 62 
J 0
(-2449 1475);
DISPLAY 0.638298 (-2449 1475);
PAINT MONO (-2449 1475);
FORCEPROP 2 LAST PATH I57
J 0
(-2175 1550);
DISPLAY 1.021277 (-2175 1550);
DISPLAY INVISIBLE (-2175 1550);
FORCEPROP 1 LAST OFFPAGE TRUE
J 2
(-2550 1350);
DISPLAY 0.872340 (-2550 1350);
PAINT AQUA (-2550 1350);
DISPLAY INVISIBLE (-2550 1350);
FORCEPROP 1 LAST COMMENT_BODY TRUE
J 2
(-2180 1380);
DISPLAY 0.872340 (-2180 1380);
PAINT GREEN (-2180 1380);
DISPLAY INVISIBLE (-2180 1380);
FORCEPROP 2 LAST CDS_LIB standard
J 0
(-2225 1475);
DISPLAY INVISIBLE (-2225 1475);
FORCEADD OFFPAGE..1
(-2225 425);
FORCEPROP 2 LAST $XR0 176 
J 0
(-2477 425);
DISPLAY 0.638298 (-2477 425);
PAINT MONO (-2477 425);
FORCEPROP 1 LAST OFFPAGE TRUE
J 0
(-1900 300);
DISPLAY 0.872340 (-1900 300);
PAINT AQUA (-1900 300);
DISPLAY INVISIBLE (-1900 300);
FORCEPROP 1 LAST COMMENT_BODY TRUE
J 0
(-2100 325);
DISPLAY 0.872340 (-2100 325);
PAINT GREEN (-2100 325);
DISPLAY INVISIBLE (-2100 325);
FORCEPROP 2 LAST CDS_LIB standard
J 0
(-2225 425);
DISPLAY INVISIBLE (-2225 425);
FORCEPROP 2 LAST PATH I59
J 0
(-2175 500);
DISPLAY 1.021277 (-2175 500);
DISPLAY INVISIBLE (-2175 500);
FORCEADD OFFPAGE..2
R 2
(2500 3075);
FORCEPROP 2 LAST $XR0 62 
J 0
(2276 3075);
DISPLAY 0.638298 (2276 3075);
PAINT MONO (2276 3075);
FORCEPROP 2 LAST CDS_LIB standard
J 0
(2500 3075);
DISPLAY INVISIBLE (2500 3075);
FORCEPROP 1 LAST COMMENT_BODY TRUE
J 2
(2545 2980);
DISPLAY 0.872340 (2545 2980);
PAINT GREEN (2545 2980);
DISPLAY INVISIBLE (2545 2980);
FORCEPROP 1 LAST OFFPAGE TRUE
J 2
(2175 2950);
DISPLAY 0.872340 (2175 2950);
PAINT AQUA (2175 2950);
DISPLAY INVISIBLE (2175 2950);
FORCEPROP 2 LAST PATH I6
J 0
(2550 3150);
DISPLAY 1.021277 (2550 3150);
DISPLAY INVISIBLE (2550 3150);
FORCEADD OFFPAGE..1
(-2225 325);
FORCEPROP 2 LAST $XR0 177 
J 0
(-2477 325);
DISPLAY 0.638298 (-2477 325);
PAINT MONO (-2477 325);
FORCEPROP 2 LAST PATH I60
J 0
(-2175 400);
DISPLAY 1.021277 (-2175 400);
DISPLAY INVISIBLE (-2175 400);
FORCEPROP 1 LAST OFFPAGE TRUE
J 0
(-1900 200);
DISPLAY 0.872340 (-1900 200);
PAINT AQUA (-1900 200);
DISPLAY INVISIBLE (-1900 200);
FORCEPROP 1 LAST COMMENT_BODY TRUE
J 0
(-2100 225);
DISPLAY 0.872340 (-2100 225);
PAINT GREEN (-2100 225);
DISPLAY INVISIBLE (-2100 225);
FORCEPROP 2 LAST CDS_LIB standard
J 0
(-2225 325);
DISPLAY INVISIBLE (-2225 325);
FORCEADD OFFPAGE..1
(-2225 275);
FORCEPROP 2 LAST $XR0 177 
J 0
(-2477 275);
DISPLAY 0.638298 (-2477 275);
PAINT MONO (-2477 275);
FORCEPROP 2 LAST PATH I61
J 0
(-2175 350);
DISPLAY 1.021277 (-2175 350);
DISPLAY INVISIBLE (-2175 350);
FORCEPROP 1 LAST OFFPAGE TRUE
J 0
(-1900 150);
DISPLAY 0.872340 (-1900 150);
PAINT AQUA (-1900 150);
DISPLAY INVISIBLE (-1900 150);
FORCEPROP 1 LAST COMMENT_BODY TRUE
J 0
(-2100 175);
DISPLAY 0.872340 (-2100 175);
PAINT GREEN (-2100 175);
DISPLAY INVISIBLE (-2100 175);
FORCEPROP 2 LAST CDS_LIB standard
J 0
(-2225 275);
DISPLAY INVISIBLE (-2225 275);
FORCEADD OFFPAGE..1
(-2225 475);
FORCEPROP 2 LAST $XR0 176 
J 0
(-2477 475);
DISPLAY 0.638298 (-2477 475);
PAINT MONO (-2477 475);
FORCEPROP 1 LAST OFFPAGE TRUE
J 0
(-1900 350);
DISPLAY 0.872340 (-1900 350);
PAINT AQUA (-1900 350);
DISPLAY INVISIBLE (-1900 350);
FORCEPROP 1 LAST COMMENT_BODY TRUE
J 0
(-2100 375);
DISPLAY 0.872340 (-2100 375);
PAINT GREEN (-2100 375);
DISPLAY INVISIBLE (-2100 375);
FORCEPROP 2 LAST CDS_LIB standard
J 0
(-2225 475);
DISPLAY INVISIBLE (-2225 475);
FORCEPROP 2 LAST PATH I62
J 0
(-2175 550);
DISPLAY 1.021277 (-2175 550);
DISPLAY INVISIBLE (-2175 550);
FORCEADD OFFPAGE..2
R 2
(-2225 775);
FORCEPROP 2 LAST $XR0 60 
J 0
(-2449 775);
DISPLAY 0.638298 (-2449 775);
PAINT MONO (-2449 775);
FORCEPROP 2 LAST PATH I63
J 0
(-2175 850);
DISPLAY 1.021277 (-2175 850);
DISPLAY INVISIBLE (-2175 850);
FORCEPROP 2 LAST CDS_LIB standard
J 0
(-2225 775);
DISPLAY INVISIBLE (-2225 775);
FORCEPROP 1 LAST COMMENT_BODY TRUE
J 2
(-2180 680);
DISPLAY 0.872340 (-2180 680);
PAINT GREEN (-2180 680);
DISPLAY INVISIBLE (-2180 680);
FORCEPROP 1 LAST OFFPAGE TRUE
J 2
(-2550 650);
DISPLAY 0.872340 (-2550 650);
PAINT AQUA (-2550 650);
DISPLAY INVISIBLE (-2550 650);
FORCEADD OFFPAGE..5
(-2225 725);
FORCEPROP 2 LAST $XR0 60 
J 0
(-2449 725);
DISPLAY 0.638298 (-2449 725);
PAINT MONO (-2449 725);
FORCEPROP 2 LAST PATH I64
J 0
(-2175 800);
DISPLAY 1.021277 (-2175 800);
DISPLAY INVISIBLE (-2175 800);
FORCEPROP 2 LAST CDS_LIB standard
J 0
(-2225 725);
DISPLAY INVISIBLE (-2225 725);
FORCEPROP 1 LAST COMMENT_BODY TRUE
J 0
(-2125 650);
DISPLAY 1.170213 (-2125 650);
PAINT GREEN (-2125 650);
DISPLAY INVISIBLE (-2125 650);
FORCEPROP 1 LAST OFFPAGE TRUE
J 0
(-1900 600);
DISPLAY 0.872340 (-1900 600);
PAINT AQUA (-1900 600);
DISPLAY INVISIBLE (-1900 600);
FORCEADD OFFPAGE..5
(-2225 575);
FORCEPROP 2 LAST $XR0 62 
J 0
(-2449 575);
DISPLAY 0.638298 (-2449 575);
PAINT MONO (-2449 575);
FORCEPROP 2 LAST PATH I65
J 0
(-2175 650);
DISPLAY 1.021277 (-2175 650);
DISPLAY INVISIBLE (-2175 650);
FORCEPROP 2 LAST CDS_LIB standard
J 0
(-2225 575);
DISPLAY INVISIBLE (-2225 575);
FORCEPROP 1 LAST COMMENT_BODY TRUE
J 0
(-2125 500);
DISPLAY 1.170213 (-2125 500);
PAINT GREEN (-2125 500);
DISPLAY INVISIBLE (-2125 500);
FORCEPROP 1 LAST OFFPAGE TRUE
J 0
(-1900 450);
DISPLAY 0.872340 (-1900 450);
PAINT AQUA (-1900 450);
DISPLAY INVISIBLE (-1900 450);
FORCEADD OFFPAGE..2
R 2
(-2225 625);
FORCEPROP 2 LAST $XR0 62 
J 0
(-2449 625);
DISPLAY 0.638298 (-2449 625);
PAINT MONO (-2449 625);
FORCEPROP 2 LAST PATH I66
J 0
(-2175 700);
DISPLAY 1.021277 (-2175 700);
DISPLAY INVISIBLE (-2175 700);
FORCEPROP 2 LAST CDS_LIB standard
J 0
(-2225 625);
DISPLAY INVISIBLE (-2225 625);
FORCEPROP 1 LAST COMMENT_BODY TRUE
J 2
(-2180 530);
DISPLAY 0.872340 (-2180 530);
PAINT GREEN (-2180 530);
DISPLAY INVISIBLE (-2180 530);
FORCEPROP 1 LAST OFFPAGE TRUE
J 2
(-2550 500);
DISPLAY 0.872340 (-2550 500);
PAINT AQUA (-2550 500);
DISPLAY INVISIBLE (-2550 500);
FORCEADD OFFPAGE..5
(2500 3175);
FORCEPROP 2 LAST $XR0 60 
J 0
(2276 3175);
DISPLAY 0.638298 (2276 3175);
PAINT MONO (2276 3175);
FORCEPROP 1 LAST OFFPAGE TRUE
J 0
(2825 3050);
DISPLAY 0.872340 (2825 3050);
PAINT AQUA (2825 3050);
DISPLAY INVISIBLE (2825 3050);
FORCEPROP 1 LAST COMMENT_BODY TRUE
J 0
(2600 3100);
DISPLAY 1.170213 (2600 3100);
PAINT GREEN (2600 3100);
DISPLAY INVISIBLE (2600 3100);
FORCEPROP 2 LAST CDS_LIB standard
J 0
(2500 3175);
DISPLAY INVISIBLE (2500 3175);
FORCEPROP 2 LAST PATH I7
J 0
(2550 3250);
DISPLAY 1.021277 (2550 3250);
DISPLAY INVISIBLE (2550 3250);
FORCEADD OFFPAGE..2
R 2
(-2225 3225);
FORCEPROP 2 LAST $XR0 60 
J 0
(-2449 3225);
DISPLAY 0.638298 (-2449 3225);
PAINT MONO (-2449 3225);
FORCEPROP 2 LAST PATH I72
J 0
(-2175 3300);
DISPLAY 1.021277 (-2175 3300);
DISPLAY INVISIBLE (-2175 3300);
FORCEPROP 2 LAST CDS_LIB standard
J 0
(-2225 3225);
DISPLAY INVISIBLE (-2225 3225);
FORCEPROP 1 LAST COMMENT_BODY TRUE
J 2
(-2180 3130);
DISPLAY 0.872340 (-2180 3130);
PAINT GREEN (-2180 3130);
DISPLAY INVISIBLE (-2180 3130);
FORCEPROP 1 LAST OFFPAGE TRUE
J 2
(-2550 3100);
DISPLAY 0.872340 (-2550 3100);
PAINT AQUA (-2550 3100);
DISPLAY INVISIBLE (-2550 3100);
FORCEADD CONN112_10137002101LF..1
(-25 1775);
FORCEPROP 1 LAST PART_NUMBER DFHSB2FR012
J 0
(-775 3525);
DISPLAY 0.723404 (-775 3525);
PAINT GREEN (-775 3525);
DISPLAY INVISIBLE (-775 3525);
FORCEPROP 2 LAST PART_TYPE THLF
J 0
(-775 3650);
DISPLAY 1.021277 (-775 3650);
FORCEPROP 1 LAST MATERIAL IO
J 0
(-770 3457);
DISPLAY 0.723404 (-770 3457);
PAINT GREEN (-770 3457);
FORCEPROP 1 LAST LOCATION J111
J 0
(-775 3575);
DISPLAY 0.723404 (-775 3575);
PAINT GREEN (-775 3575);
FORCEPROP 0 LASTPIN (-950 875) $PN A5
J 2
(-960 885);
DISPLAY 0.680851 (-960 885);
PAINT MONO (-960 885);
FORCEPROP 0 LASTPIN (-950 1675) $PN A6
J 2
(-960 1685);
DISPLAY 0.680851 (-960 1685);
PAINT MONO (-960 1685);
FORCEPROP 0 LASTPIN (-950 2475) $PN A7
J 2
(-960 2485);
DISPLAY 0.680851 (-960 2485);
PAINT MONO (-960 2485);
FORCEPROP 0 LASTPIN (-950 3275) $PN A8
J 2
(-960 3285);
DISPLAY 0.680851 (-960 3285);
PAINT MONO (-960 3285);
FORCEPROP 0 LASTPIN (-950 825) $PN B5
J 2
(-960 835);
DISPLAY 0.680851 (-960 835);
PAINT MONO (-960 835);
FORCEPROP 0 LASTPIN (-950 1625) $PN B6
J 2
(-960 1635);
DISPLAY 0.680851 (-960 1635);
PAINT MONO (-960 1635);
FORCEPROP 0 LASTPIN (-950 2425) $PN B7
J 2
(-960 2435);
DISPLAY 0.680851 (-960 2435);
PAINT MONO (-960 2435);
FORCEPROP 0 LASTPIN (-950 3225) $PN B8
J 2
(-960 3235);
DISPLAY 0.680851 (-960 3235);
PAINT MONO (-960 3235);
FORCEPROP 0 LASTPIN (-950 775) $PN C5
J 2
(-960 785);
DISPLAY 0.680851 (-960 785);
PAINT MONO (-960 785);
FORCEPROP 0 LASTPIN (-950 1575) $PN C6
J 2
(-960 1585);
DISPLAY 0.680851 (-960 1585);
PAINT MONO (-960 1585);
FORCEPROP 0 LASTPIN (-950 2375) $PN C7
J 2
(-960 2385);
DISPLAY 0.680851 (-960 2385);
PAINT MONO (-960 2385);
FORCEPROP 0 LASTPIN (-950 3175) $PN C8
J 2
(-960 3185);
DISPLAY 0.680851 (-960 3185);
PAINT MONO (-960 3185);
FORCEPROP 0 LASTPIN (-950 725) $PN D5
J 2
(-960 735);
DISPLAY 0.680851 (-960 735);
PAINT MONO (-960 735);
FORCEPROP 0 LASTPIN (-950 1525) $PN D6
J 2
(-960 1535);
DISPLAY 0.680851 (-960 1535);
PAINT MONO (-960 1535);
FORCEPROP 0 LASTPIN (-950 2325) $PN D7
J 2
(-960 2335);
DISPLAY 0.680851 (-960 2335);
PAINT MONO (-960 2335);
FORCEPROP 0 LASTPIN (-950 3125) $PN D8
J 2
(-960 3135);
DISPLAY 0.680851 (-960 3135);
PAINT MONO (-960 3135);
FORCEPROP 0 LASTPIN (-950 675) $PN E5
J 2
(-960 685);
DISPLAY 0.680851 (-960 685);
PAINT MONO (-960 685);
FORCEPROP 0 LASTPIN (-950 1475) $PN E6
J 2
(-960 1485);
DISPLAY 0.680851 (-960 1485);
PAINT MONO (-960 1485);
FORCEPROP 0 LASTPIN (-950 2275) $PN E7
J 2
(-960 2285);
DISPLAY 0.680851 (-960 2285);
PAINT MONO (-960 2285);
FORCEPROP 0 LASTPIN (-950 3075) $PN E8
J 2
(-960 3085);
DISPLAY 0.680851 (-960 3085);
PAINT MONO (-960 3085);
FORCEPROP 0 LASTPIN (-950 625) $PN F5
J 2
(-960 635);
DISPLAY 0.680851 (-960 635);
PAINT MONO (-960 635);
FORCEPROP 0 LASTPIN (-950 1425) $PN F6
J 2
(-960 1435);
DISPLAY 0.680851 (-960 1435);
PAINT MONO (-960 1435);
FORCEPROP 0 LASTPIN (-950 2225) $PN F7
J 2
(-960 2235);
DISPLAY 0.680851 (-960 2235);
PAINT MONO (-960 2235);
FORCEPROP 0 LASTPIN (-950 3025) $PN F8
J 2
(-960 3035);
DISPLAY 0.680851 (-960 3035);
PAINT MONO (-960 3035);
FORCEPROP 0 LASTPIN (-950 575) $PN G5
J 2
(-960 585);
DISPLAY 0.680851 (-960 585);
PAINT MONO (-960 585);
FORCEPROP 0 LASTPIN (-950 1375) $PN G6
J 2
(-960 1385);
DISPLAY 0.680851 (-960 1385);
PAINT MONO (-960 1385);
FORCEPROP 0 LASTPIN (-950 2175) $PN G7
J 2
(-960 2185);
DISPLAY 0.680851 (-960 2185);
PAINT MONO (-960 2185);
FORCEPROP 0 LASTPIN (-950 2975) $PN G8
J 2
(-960 2985);
DISPLAY 0.680851 (-960 2985);
PAINT MONO (-960 2985);
FORCEPROP 0 LASTPIN (-950 525) $PN H5
J 2
(-960 535);
DISPLAY 0.680851 (-960 535);
PAINT MONO (-960 535);
FORCEPROP 0 LASTPIN (-950 1325) $PN H6
J 2
(-960 1335);
DISPLAY 0.680851 (-960 1335);
PAINT MONO (-960 1335);
FORCEPROP 0 LASTPIN (-950 2125) $PN H7
J 2
(-960 2135);
DISPLAY 0.680851 (-960 2135);
PAINT MONO (-960 2135);
FORCEPROP 0 LASTPIN (-950 2925) $PN H8
J 2
(-960 2935);
DISPLAY 0.680851 (-960 2935);
PAINT MONO (-960 2935);
FORCEPROP 0 LASTPIN (-950 475) $PN I5
J 2
(-960 485);
DISPLAY 0.680851 (-960 485);
PAINT MONO (-960 485);
FORCEPROP 0 LASTPIN (-950 1275) $PN I6
J 2
(-960 1285);
DISPLAY 0.680851 (-960 1285);
PAINT MONO (-960 1285);
FORCEPROP 0 LASTPIN (-950 2075) $PN I7
J 2
(-960 2085);
DISPLAY 0.680851 (-960 2085);
PAINT MONO (-960 2085);
FORCEPROP 0 LASTPIN (-950 2875) $PN I8
J 2
(-960 2885);
DISPLAY 0.680851 (-960 2885);
PAINT MONO (-960 2885);
FORCEPROP 0 LASTPIN (-950 425) $PN J5
J 2
(-960 435);
DISPLAY 0.680851 (-960 435);
PAINT MONO (-960 435);
FORCEPROP 0 LASTPIN (-950 1225) $PN J6
J 2
(-960 1235);
DISPLAY 0.680851 (-960 1235);
PAINT MONO (-960 1235);
FORCEPROP 0 LASTPIN (-950 2025) $PN J7
J 2
(-960 2035);
DISPLAY 0.680851 (-960 2035);
PAINT MONO (-960 2035);
FORCEPROP 0 LASTPIN (-950 2825) $PN J8
J 2
(-960 2835);
DISPLAY 0.680851 (-960 2835);
PAINT MONO (-960 2835);
FORCEPROP 0 LASTPIN (-950 375) $PN K5
J 2
(-960 385);
DISPLAY 0.680851 (-960 385);
PAINT MONO (-960 385);
FORCEPROP 0 LASTPIN (-950 1175) $PN K6
J 2
(-960 1185);
DISPLAY 0.680851 (-960 1185);
PAINT MONO (-960 1185);
FORCEPROP 0 LASTPIN (-950 1975) $PN K7
J 2
(-960 1985);
DISPLAY 0.680851 (-960 1985);
PAINT MONO (-960 1985);
FORCEPROP 0 LASTPIN (-950 2775) $PN K8
J 2
(-960 2785);
DISPLAY 0.680851 (-960 2785);
PAINT MONO (-960 2785);
FORCEPROP 0 LASTPIN (-950 325) $PN L5
J 2
(-960 335);
DISPLAY 0.680851 (-960 335);
PAINT MONO (-960 335);
FORCEPROP 0 LASTPIN (-950 1125) $PN L6
J 2
(-960 1135);
DISPLAY 0.680851 (-960 1135);
PAINT MONO (-960 1135);
FORCEPROP 0 LASTPIN (-950 1925) $PN L7
J 2
(-960 1935);
DISPLAY 0.680851 (-960 1935);
PAINT MONO (-960 1935);
FORCEPROP 0 LASTPIN (-950 2725) $PN L8
J 2
(-960 2735);
DISPLAY 0.680851 (-960 2735);
PAINT MONO (-960 2735);
FORCEPROP 0 LASTPIN (-950 275) $PN M5
J 2
(-960 285);
DISPLAY 0.680851 (-960 285);
PAINT MONO (-960 285);
FORCEPROP 0 LASTPIN (-950 1075) $PN M6
J 2
(-960 1085);
DISPLAY 0.680851 (-960 1085);
PAINT MONO (-960 1085);
FORCEPROP 0 LASTPIN (-950 1875) $PN M7
J 2
(-960 1885);
DISPLAY 0.680851 (-960 1885);
PAINT MONO (-960 1885);
FORCEPROP 0 LASTPIN (-950 2675) $PN M8
J 2
(-960 2685);
DISPLAY 0.680851 (-960 2685);
PAINT MONO (-960 2685);
FORCEPROP 0 LASTPIN (-950 225) $PN N5
J 2
(-960 235);
DISPLAY 0.680851 (-960 235);
PAINT MONO (-960 235);
FORCEPROP 0 LASTPIN (-950 1025) $PN N6
J 2
(-960 1035);
DISPLAY 0.680851 (-960 1035);
PAINT MONO (-960 1035);
FORCEPROP 0 LASTPIN (-950 1825) $PN N7
J 2
(-960 1835);
DISPLAY 0.680851 (-960 1835);
PAINT MONO (-960 1835);
FORCEPROP 0 LASTPIN (-950 2625) $PN N8
J 2
(-960 2635);
DISPLAY 0.680851 (-960 2635);
PAINT MONO (-960 2635);
FORCEPROP 2 LAST CDS_LIB pure_quanta
J 0
(-25 1775);
DISPLAY INVISIBLE (-25 1775);
FORCEPROP 1 LAST PATH I74
J 0
(-25 1775);
DISPLAY 0.723404 (-25 1775);
PAINT GREEN (-25 1775);
DISPLAY INVISIBLE (-25 1775);
FORCEPROP 1 LAST NEEDS_NO_SIZE TRUE
J 0
(-25 1775);
DISPLAY 0.723404 (-25 1775);
PAINT GREEN (-25 1775);
DISPLAY INVISIBLE (-25 1775);
FORCEPROP 1 LAST CDS_LMAN_SYM_OUTLINE -775,1650,775,-1650
J 0
(-25 1775);
DISPLAY 0.468085 (-25 1775);
PAINT GREEN (-25 1775);
DISPLAY INVISIBLE (-25 1775);
FORCEPROP 0 LAST VALUE CONN112_10137002-101LF
J 0
(-750 3775);
DISPLAY 1.021277 (-750 3775);
DISPLAY INVISIBLE (-750 3775);
FORCEPROP 0 LAST $SEC 1
J 0
(-775 3700);
DISPLAY 0.680851 (-775 3700);
PAINT MONO (-775 3700);
DISPLAY INVISIBLE (-775 3700);
FORCEPROP 0 LAST CDS_SEC 1
J 0
(-775 3700);
DISPLAY 1.021277 (-775 3700);
DISPLAY INVISIBLE (-775 3700);
FORCEADD CONN112_10137002101LF..2
(4725 1775);
FORCEPROP 1 LAST PART_NUMBER DFHSB2FR012
J 0
(3975 3550);
DISPLAY 0.723404 (3975 3550);
PAINT GREEN (3975 3550);
DISPLAY INVISIBLE (3975 3550);
FORCEPROP 2 LAST PART_TYPE THLF
J 0
(3975 3675);
DISPLAY 1.021277 (3975 3675);
FORCEPROP 1 LAST MATERIAL IO
J 0
(3983 3488);
DISPLAY 0.723404 (3983 3488);
PAINT GREEN (3983 3488);
FORCEPROP 1 LAST LOCATION J111
J 0
(3975 3600);
DISPLAY 0.723404 (3975 3600);
PAINT GREEN (3975 3600);
FORCEPROP 0 LASTPIN (3800 875) $PN A1
J 2
(3790 885);
DISPLAY 0.680851 (3790 885);
PAINT MONO (3790 885);
FORCEPROP 0 LASTPIN (3800 1675) $PN A2
J 2
(3790 1685);
DISPLAY 0.680851 (3790 1685);
PAINT MONO (3790 1685);
FORCEPROP 0 LASTPIN (3800 2475) $PN A3
J 2
(3790 2485);
DISPLAY 0.680851 (3790 2485);
PAINT MONO (3790 2485);
FORCEPROP 0 LASTPIN (3800 3275) $PN A4
J 2
(3790 3285);
DISPLAY 0.680851 (3790 3285);
PAINT MONO (3790 3285);
FORCEPROP 0 LASTPIN (3800 825) $PN B1
J 2
(3790 835);
DISPLAY 0.680851 (3790 835);
PAINT MONO (3790 835);
FORCEPROP 0 LASTPIN (3800 1625) $PN B2
J 2
(3790 1635);
DISPLAY 0.680851 (3790 1635);
PAINT MONO (3790 1635);
FORCEPROP 0 LASTPIN (3800 2425) $PN B3
J 2
(3790 2435);
DISPLAY 0.680851 (3790 2435);
PAINT MONO (3790 2435);
FORCEPROP 0 LASTPIN (3800 3225) $PN B4
J 2
(3790 3235);
DISPLAY 0.680851 (3790 3235);
PAINT MONO (3790 3235);
FORCEPROP 0 LASTPIN (3800 775) $PN C1
J 2
(3790 785);
DISPLAY 0.680851 (3790 785);
PAINT MONO (3790 785);
FORCEPROP 0 LASTPIN (3800 1575) $PN C2
J 2
(3790 1585);
DISPLAY 0.680851 (3790 1585);
PAINT MONO (3790 1585);
FORCEPROP 0 LASTPIN (3800 2375) $PN C3
J 2
(3790 2385);
DISPLAY 0.680851 (3790 2385);
PAINT MONO (3790 2385);
FORCEPROP 0 LASTPIN (3800 3175) $PN C4
J 2
(3790 3185);
DISPLAY 0.680851 (3790 3185);
PAINT MONO (3790 3185);
FORCEPROP 0 LASTPIN (3800 725) $PN D1
J 2
(3790 735);
DISPLAY 0.680851 (3790 735);
PAINT MONO (3790 735);
FORCEPROP 0 LASTPIN (3800 1525) $PN D2
J 2
(3790 1535);
DISPLAY 0.680851 (3790 1535);
PAINT MONO (3790 1535);
FORCEPROP 0 LASTPIN (3800 2325) $PN D3
J 2
(3790 2335);
DISPLAY 0.680851 (3790 2335);
PAINT MONO (3790 2335);
FORCEPROP 0 LASTPIN (3800 3125) $PN D4
J 2
(3790 3135);
DISPLAY 0.680851 (3790 3135);
PAINT MONO (3790 3135);
FORCEPROP 0 LASTPIN (3800 675) $PN E1
J 2
(3790 685);
DISPLAY 0.680851 (3790 685);
PAINT MONO (3790 685);
FORCEPROP 0 LASTPIN (3800 1475) $PN E2
J 2
(3790 1485);
DISPLAY 0.680851 (3790 1485);
PAINT MONO (3790 1485);
FORCEPROP 0 LASTPIN (3800 2275) $PN E3
J 2
(3790 2285);
DISPLAY 0.680851 (3790 2285);
PAINT MONO (3790 2285);
FORCEPROP 0 LASTPIN (3800 3075) $PN E4
J 2
(3790 3085);
DISPLAY 0.680851 (3790 3085);
PAINT MONO (3790 3085);
FORCEPROP 0 LASTPIN (3800 625) $PN F1
J 2
(3790 635);
DISPLAY 0.680851 (3790 635);
PAINT MONO (3790 635);
FORCEPROP 0 LASTPIN (3800 1425) $PN F2
J 2
(3790 1435);
DISPLAY 0.680851 (3790 1435);
PAINT MONO (3790 1435);
FORCEPROP 0 LASTPIN (3800 2225) $PN F3
J 2
(3790 2235);
DISPLAY 0.680851 (3790 2235);
PAINT MONO (3790 2235);
FORCEPROP 0 LASTPIN (3800 3025) $PN F4
J 2
(3790 3035);
DISPLAY 0.680851 (3790 3035);
PAINT MONO (3790 3035);
FORCEPROP 0 LASTPIN (3800 575) $PN G1
J 2
(3790 585);
DISPLAY 0.680851 (3790 585);
PAINT MONO (3790 585);
FORCEPROP 0 LASTPIN (3800 1375) $PN G2
J 2
(3790 1385);
DISPLAY 0.680851 (3790 1385);
PAINT MONO (3790 1385);
FORCEPROP 0 LASTPIN (3800 2175) $PN G3
J 2
(3790 2185);
DISPLAY 0.680851 (3790 2185);
PAINT MONO (3790 2185);
FORCEPROP 0 LASTPIN (3800 2975) $PN G4
J 2
(3790 2985);
DISPLAY 0.680851 (3790 2985);
PAINT MONO (3790 2985);
FORCEPROP 0 LASTPIN (3800 525) $PN H1
J 2
(3790 535);
DISPLAY 0.680851 (3790 535);
PAINT MONO (3790 535);
FORCEPROP 0 LASTPIN (3800 1325) $PN H2
J 2
(3790 1335);
DISPLAY 0.680851 (3790 1335);
PAINT MONO (3790 1335);
FORCEPROP 0 LASTPIN (3800 2125) $PN H3
J 2
(3790 2135);
DISPLAY 0.680851 (3790 2135);
PAINT MONO (3790 2135);
FORCEPROP 0 LASTPIN (3800 2925) $PN H4
J 2
(3790 2935);
DISPLAY 0.680851 (3790 2935);
PAINT MONO (3790 2935);
FORCEPROP 0 LASTPIN (3800 475) $PN I1
J 2
(3790 485);
DISPLAY 0.680851 (3790 485);
PAINT MONO (3790 485);
FORCEPROP 0 LASTPIN (3800 1275) $PN I2
J 2
(3790 1285);
DISPLAY 0.680851 (3790 1285);
PAINT MONO (3790 1285);
FORCEPROP 0 LASTPIN (3800 2075) $PN I3
J 2
(3790 2085);
DISPLAY 0.680851 (3790 2085);
PAINT MONO (3790 2085);
FORCEPROP 0 LASTPIN (3800 2875) $PN I4
J 2
(3790 2885);
DISPLAY 0.680851 (3790 2885);
PAINT MONO (3790 2885);
FORCEPROP 0 LASTPIN (3800 425) $PN J1
J 2
(3790 435);
DISPLAY 0.680851 (3790 435);
PAINT MONO (3790 435);
FORCEPROP 0 LASTPIN (3800 1225) $PN J2
J 2
(3790 1235);
DISPLAY 0.680851 (3790 1235);
PAINT MONO (3790 1235);
FORCEPROP 0 LASTPIN (3800 2025) $PN J3
J 2
(3790 2035);
DISPLAY 0.680851 (3790 2035);
PAINT MONO (3790 2035);
FORCEPROP 0 LASTPIN (3800 2825) $PN J4
J 2
(3790 2835);
DISPLAY 0.680851 (3790 2835);
PAINT MONO (3790 2835);
FORCEPROP 0 LASTPIN (3800 375) $PN K1
J 2
(3790 385);
DISPLAY 0.680851 (3790 385);
PAINT MONO (3790 385);
FORCEPROP 0 LASTPIN (3800 1175) $PN K2
J 2
(3790 1185);
DISPLAY 0.680851 (3790 1185);
PAINT MONO (3790 1185);
FORCEPROP 0 LASTPIN (3800 1975) $PN K3
J 2
(3790 1985);
DISPLAY 0.680851 (3790 1985);
PAINT MONO (3790 1985);
FORCEPROP 0 LASTPIN (3800 2775) $PN K4
J 2
(3790 2785);
DISPLAY 0.680851 (3790 2785);
PAINT MONO (3790 2785);
FORCEPROP 0 LASTPIN (3800 325) $PN L1
J 2
(3790 335);
DISPLAY 0.680851 (3790 335);
PAINT MONO (3790 335);
FORCEPROP 0 LASTPIN (3800 1125) $PN L2
J 2
(3790 1135);
DISPLAY 0.680851 (3790 1135);
PAINT MONO (3790 1135);
FORCEPROP 0 LASTPIN (3800 1925) $PN L3
J 2
(3790 1935);
DISPLAY 0.680851 (3790 1935);
PAINT MONO (3790 1935);
FORCEPROP 0 LASTPIN (3800 2725) $PN L4
J 2
(3790 2735);
DISPLAY 0.680851 (3790 2735);
PAINT MONO (3790 2735);
FORCEPROP 0 LASTPIN (3800 275) $PN M1
J 2
(3790 285);
DISPLAY 0.680851 (3790 285);
PAINT MONO (3790 285);
FORCEPROP 0 LASTPIN (3800 1075) $PN M2
J 2
(3790 1085);
DISPLAY 0.680851 (3790 1085);
PAINT MONO (3790 1085);
FORCEPROP 0 LASTPIN (3800 1875) $PN M3
J 2
(3790 1885);
DISPLAY 0.680851 (3790 1885);
PAINT MONO (3790 1885);
FORCEPROP 0 LASTPIN (3800 2675) $PN M4
J 2
(3790 2685);
DISPLAY 0.680851 (3790 2685);
PAINT MONO (3790 2685);
FORCEPROP 0 LASTPIN (3800 225) $PN N1
J 2
(3790 235);
DISPLAY 0.680851 (3790 235);
PAINT MONO (3790 235);
FORCEPROP 0 LASTPIN (3800 1025) $PN N2
J 2
(3790 1035);
DISPLAY 0.680851 (3790 1035);
PAINT MONO (3790 1035);
FORCEPROP 0 LASTPIN (3800 1825) $PN N3
J 2
(3790 1835);
DISPLAY 0.680851 (3790 1835);
PAINT MONO (3790 1835);
FORCEPROP 0 LASTPIN (3800 2625) $PN N4
J 2
(3790 2635);
DISPLAY 0.680851 (3790 2635);
PAINT MONO (3790 2635);
FORCEPROP 0 LAST VALUE CONN112_10137002-101LF
J 0
(3975 3675);
DISPLAY 1.021277 (3975 3675);
DISPLAY INVISIBLE (3975 3675);
FORCEPROP 2 LAST CDS_LIB pure_quanta
J 0
(4725 1775);
DISPLAY INVISIBLE (4725 1775);
FORCEPROP 1 LAST PATH I75
J 0
(4725 1775);
DISPLAY 0.723404 (4725 1775);
PAINT GREEN (4725 1775);
DISPLAY INVISIBLE (4725 1775);
FORCEPROP 1 LAST NEEDS_NO_SIZE TRUE
J 0
(4725 1775);
DISPLAY 0.723404 (4725 1775);
PAINT GREEN (4725 1775);
DISPLAY INVISIBLE (4725 1775);
FORCEPROP 1 LAST CDS_LMAN_SYM_OUTLINE -775,1650,775,-1650
J 0
(4725 1775);
DISPLAY 0.468085 (4725 1775);
PAINT GREEN (4725 1775);
DISPLAY INVISIBLE (4725 1775);
FORCEPROP 0 LAST $SEC 2
J 0
(3975 3725);
DISPLAY 0.680851 (3975 3725);
PAINT MONO (3975 3725);
DISPLAY INVISIBLE (3975 3725);
FORCEPROP 0 LAST CDS_SEC 2
J 0
(3975 3725);
DISPLAY 1.021277 (3975 3725);
DISPLAY INVISIBLE (3975 3725);
FORCEADD OFFPAGE..2
R 2
(2500 775);
FORCEPROP 2 LAST $XR0 60 
J 0
(2276 775);
DISPLAY 0.638298 (2276 775);
PAINT MONO (2276 775);
FORCEPROP 2 LAST PATH I76
J 0
(2550 850);
DISPLAY 1.021277 (2550 850);
DISPLAY INVISIBLE (2550 850);
FORCEPROP 2 LAST CDS_LIB standard
J 0
(2500 775);
DISPLAY INVISIBLE (2500 775);
FORCEPROP 1 LAST COMMENT_BODY TRUE
J 2
(2545 680);
DISPLAY 0.872340 (2545 680);
PAINT GREEN (2545 680);
DISPLAY INVISIBLE (2545 680);
FORCEPROP 1 LAST OFFPAGE TRUE
J 2
(2175 650);
DISPLAY 0.872340 (2175 650);
PAINT AQUA (2175 650);
DISPLAY INVISIBLE (2175 650);
FORCEADD OFFPAGE..5
(2500 725);
FORCEPROP 2 LAST $XR0 60 
J 0
(2276 725);
DISPLAY 0.638298 (2276 725);
PAINT MONO (2276 725);
FORCEPROP 2 LAST PATH I77
J 0
(2550 800);
DISPLAY 1.021277 (2550 800);
DISPLAY INVISIBLE (2550 800);
FORCEPROP 2 LAST CDS_LIB standard
J 0
(2500 725);
DISPLAY INVISIBLE (2500 725);
FORCEPROP 1 LAST COMMENT_BODY TRUE
J 0
(2600 650);
DISPLAY 1.170213 (2600 650);
PAINT GREEN (2600 650);
DISPLAY INVISIBLE (2600 650);
FORCEPROP 1 LAST OFFPAGE TRUE
J 0
(2825 600);
DISPLAY 0.872340 (2825 600);
PAINT AQUA (2825 600);
DISPLAY INVISIBLE (2825 600);
FORCEADD OFFPAGE..2
R 2
(2500 625);
FORCEPROP 2 LAST $XR0 62 
J 0
(2276 625);
DISPLAY 0.638298 (2276 625);
PAINT MONO (2276 625);
FORCEPROP 2 LAST PATH I78
J 0
(2550 700);
DISPLAY 1.021277 (2550 700);
DISPLAY INVISIBLE (2550 700);
FORCEPROP 2 LAST CDS_LIB standard
J 0
(2500 625);
DISPLAY INVISIBLE (2500 625);
FORCEPROP 1 LAST COMMENT_BODY TRUE
J 2
(2545 530);
DISPLAY 0.872340 (2545 530);
PAINT GREEN (2545 530);
DISPLAY INVISIBLE (2545 530);
FORCEPROP 1 LAST OFFPAGE TRUE
J 2
(2175 500);
DISPLAY 0.872340 (2175 500);
PAINT AQUA (2175 500);
DISPLAY INVISIBLE (2175 500);
FORCEADD OFFPAGE..5
(2500 575);
FORCEPROP 2 LAST $XR0 62 
J 0
(2276 575);
DISPLAY 0.638298 (2276 575);
PAINT MONO (2276 575);
FORCEPROP 2 LAST PATH I79
J 0
(2550 650);
DISPLAY 1.021277 (2550 650);
DISPLAY INVISIBLE (2550 650);
FORCEPROP 2 LAST CDS_LIB standard
J 0
(2500 575);
DISPLAY INVISIBLE (2500 575);
FORCEPROP 1 LAST COMMENT_BODY TRUE
J 0
(2600 500);
DISPLAY 1.170213 (2600 500);
PAINT GREEN (2600 500);
DISPLAY INVISIBLE (2600 500);
FORCEPROP 1 LAST OFFPAGE TRUE
J 0
(2825 450);
DISPLAY 0.872340 (2825 450);
PAINT AQUA (2825 450);
DISPLAY INVISIBLE (2825 450);
FORCEADD OFFPAGE..2
R 2
(2500 3225);
FORCEPROP 2 LAST $XR0 60 
J 0
(2276 3225);
DISPLAY 0.638298 (2276 3225);
PAINT MONO (2276 3225);
FORCEPROP 1 LAST OFFPAGE TRUE
J 2
(2175 3100);
DISPLAY 0.872340 (2175 3100);
PAINT AQUA (2175 3100);
DISPLAY INVISIBLE (2175 3100);
FORCEPROP 1 LAST COMMENT_BODY TRUE
J 2
(2545 3130);
DISPLAY 0.872340 (2545 3130);
PAINT GREEN (2545 3130);
DISPLAY INVISIBLE (2545 3130);
FORCEPROP 2 LAST CDS_LIB standard
J 0
(2500 3225);
DISPLAY INVISIBLE (2500 3225);
FORCEPROP 2 LAST PATH I8
J 0
(2550 3300);
DISPLAY 1.021277 (2550 3300);
DISPLAY INVISIBLE (2550 3300);
FORCEADD OFFPAGE..1
(2500 475);
FORCEPROP 2 LAST $XR0 176 
J 0
(2248 475);
DISPLAY 0.638298 (2248 475);
PAINT MONO (2248 475);
FORCEPROP 2 LAST PATH I80
J 0
(2550 550);
DISPLAY 1.021277 (2550 550);
DISPLAY INVISIBLE (2550 550);
FORCEPROP 1 LAST OFFPAGE TRUE
J 0
(2825 350);
DISPLAY 0.872340 (2825 350);
PAINT AQUA (2825 350);
DISPLAY INVISIBLE (2825 350);
FORCEPROP 1 LAST COMMENT_BODY TRUE
J 0
(2625 375);
DISPLAY 0.872340 (2625 375);
PAINT GREEN (2625 375);
DISPLAY INVISIBLE (2625 375);
FORCEPROP 2 LAST CDS_LIB standard
J 0
(2500 475);
DISPLAY INVISIBLE (2500 475);
FORCEADD OFFPAGE..1
(2500 425);
FORCEPROP 2 LAST $XR0 176 
J 0
(2248 425);
DISPLAY 0.638298 (2248 425);
PAINT MONO (2248 425);
FORCEPROP 2 LAST PATH I81
J 0
(2550 500);
DISPLAY 1.021277 (2550 500);
DISPLAY INVISIBLE (2550 500);
FORCEPROP 1 LAST OFFPAGE TRUE
J 0
(2825 300);
DISPLAY 0.872340 (2825 300);
PAINT AQUA (2825 300);
DISPLAY INVISIBLE (2825 300);
FORCEPROP 1 LAST COMMENT_BODY TRUE
J 0
(2625 325);
DISPLAY 0.872340 (2625 325);
PAINT GREEN (2625 325);
DISPLAY INVISIBLE (2625 325);
FORCEPROP 2 LAST CDS_LIB standard
J 0
(2500 425);
DISPLAY INVISIBLE (2500 425);
FORCEADD OFFPAGE..1
(2500 275);
FORCEPROP 2 LAST $XR0 177 
J 0
(2248 275);
DISPLAY 0.638298 (2248 275);
PAINT MONO (2248 275);
FORCEPROP 2 LAST PATH I82
J 0
(2550 350);
DISPLAY 1.021277 (2550 350);
DISPLAY INVISIBLE (2550 350);
FORCEPROP 2 LAST CDS_LIB standard
J 0
(2500 275);
DISPLAY INVISIBLE (2500 275);
FORCEPROP 1 LAST COMMENT_BODY TRUE
J 0
(2625 175);
DISPLAY 0.872340 (2625 175);
PAINT GREEN (2625 175);
DISPLAY INVISIBLE (2625 175);
FORCEPROP 1 LAST OFFPAGE TRUE
J 0
(2825 150);
DISPLAY 0.872340 (2825 150);
PAINT AQUA (2825 150);
DISPLAY INVISIBLE (2825 150);
FORCEADD OFFPAGE..1
(2500 325);
FORCEPROP 2 LAST $XR0 177 
J 0
(2248 325);
DISPLAY 0.638298 (2248 325);
PAINT MONO (2248 325);
FORCEPROP 2 LAST PATH I83
J 0
(2550 400);
DISPLAY 1.021277 (2550 400);
DISPLAY INVISIBLE (2550 400);
FORCEPROP 2 LAST CDS_LIB standard
J 0
(2500 325);
DISPLAY INVISIBLE (2500 325);
FORCEPROP 1 LAST COMMENT_BODY TRUE
J 0
(2625 225);
DISPLAY 0.872340 (2625 225);
PAINT GREEN (2625 225);
DISPLAY INVISIBLE (2625 225);
FORCEPROP 1 LAST OFFPAGE TRUE
J 0
(2825 200);
DISPLAY 0.872340 (2825 200);
PAINT AQUA (2825 200);
DISPLAY INVISIBLE (2825 200);
FORCEADD OFFPAGE..5
(2500 1425);
FORCEPROP 2 LAST $XR0 62 
J 0
(2276 1425);
DISPLAY 0.638298 (2276 1425);
PAINT MONO (2276 1425);
FORCEPROP 2 LAST CDS_LIB standard
J 0
(2500 1425);
DISPLAY INVISIBLE (2500 1425);
FORCEPROP 2 LAST PATH I84
J 0
(2550 1500);
DISPLAY 1.021277 (2550 1500);
DISPLAY INVISIBLE (2550 1500);
FORCEPROP 1 LAST COMMENT_BODY TRUE
J 0
(2600 1350);
DISPLAY 1.170213 (2600 1350);
PAINT GREEN (2600 1350);
DISPLAY INVISIBLE (2600 1350);
FORCEPROP 1 LAST OFFPAGE TRUE
J 0
(2825 1300);
DISPLAY 0.872340 (2825 1300);
PAINT AQUA (2825 1300);
DISPLAY INVISIBLE (2825 1300);
FORCEADD OFFPAGE..2
R 2
(2500 1475);
FORCEPROP 2 LAST $XR0 62 
J 0
(2276 1475);
DISPLAY 0.638298 (2276 1475);
PAINT MONO (2276 1475);
FORCEPROP 1 LAST OFFPAGE TRUE
J 2
(2175 1350);
DISPLAY 0.872340 (2175 1350);
PAINT AQUA (2175 1350);
DISPLAY INVISIBLE (2175 1350);
FORCEPROP 1 LAST COMMENT_BODY TRUE
J 2
(2545 1380);
DISPLAY 0.872340 (2545 1380);
PAINT GREEN (2545 1380);
DISPLAY INVISIBLE (2545 1380);
FORCEPROP 2 LAST CDS_LIB standard
J 0
(2500 1475);
DISPLAY INVISIBLE (2500 1475);
FORCEPROP 2 LAST PATH I85
J 0
(2550 1550);
DISPLAY 1.021277 (2550 1550);
DISPLAY INVISIBLE (2550 1550);
FORCEADD OFFPAGE..5
(2500 1575);
FORCEPROP 2 LAST $XR0 60 
J 0
(2276 1575);
DISPLAY 0.638298 (2276 1575);
PAINT MONO (2276 1575);
FORCEPROP 2 LAST CDS_LIB standard
J 0
(2500 1575);
DISPLAY INVISIBLE (2500 1575);
FORCEPROP 1 LAST COMMENT_BODY TRUE
J 0
(2600 1500);
DISPLAY 1.170213 (2600 1500);
PAINT GREEN (2600 1500);
DISPLAY INVISIBLE (2600 1500);
FORCEPROP 1 LAST OFFPAGE TRUE
J 0
(2825 1450);
DISPLAY 0.872340 (2825 1450);
PAINT AQUA (2825 1450);
DISPLAY INVISIBLE (2825 1450);
FORCEPROP 2 LAST PATH I86
J 0
(2550 1650);
DISPLAY 1.021277 (2550 1650);
DISPLAY INVISIBLE (2550 1650);
FORCEADD OFFPAGE..2
R 2
(2500 1625);
FORCEPROP 2 LAST $XR0 60 
J 0
(2276 1625);
DISPLAY 0.638298 (2276 1625);
PAINT MONO (2276 1625);
FORCEPROP 2 LAST CDS_LIB standard
J 0
(2500 1625);
DISPLAY INVISIBLE (2500 1625);
FORCEPROP 1 LAST COMMENT_BODY TRUE
J 2
(2545 1530);
DISPLAY 0.872340 (2545 1530);
PAINT GREEN (2545 1530);
DISPLAY INVISIBLE (2545 1530);
FORCEPROP 1 LAST OFFPAGE TRUE
J 2
(2175 1500);
DISPLAY 0.872340 (2175 1500);
PAINT AQUA (2175 1500);
DISPLAY INVISIBLE (2175 1500);
FORCEPROP 2 LAST PATH I87
J 0
(2550 1700);
DISPLAY 1.021277 (2550 1700);
DISPLAY INVISIBLE (2550 1700);
FORCEADD OFFPAGE..1
(2500 1325);
FORCEPROP 2 LAST $XR0 176 
J 0
(2248 1325);
DISPLAY 0.638298 (2248 1325);
PAINT MONO (2248 1325);
FORCEPROP 2 LAST CDS_LIB standard
J 0
(2500 1325);
DISPLAY INVISIBLE (2500 1325);
FORCEPROP 1 LAST COMMENT_BODY TRUE
J 0
(2625 1225);
DISPLAY 0.872340 (2625 1225);
PAINT GREEN (2625 1225);
DISPLAY INVISIBLE (2625 1225);
FORCEPROP 1 LAST OFFPAGE TRUE
J 0
(2825 1200);
DISPLAY 0.872340 (2825 1200);
PAINT AQUA (2825 1200);
DISPLAY INVISIBLE (2825 1200);
FORCEPROP 2 LAST PATH I88
J 0
(2550 1400);
DISPLAY 1.021277 (2550 1400);
DISPLAY INVISIBLE (2550 1400);
FORCEADD OFFPAGE..1
(2500 1275);
FORCEPROP 2 LAST $XR0 176 
J 0
(2248 1275);
DISPLAY 0.638298 (2248 1275);
PAINT MONO (2248 1275);
FORCEPROP 2 LAST CDS_LIB standard
J 0
(2500 1275);
DISPLAY INVISIBLE (2500 1275);
FORCEPROP 1 LAST COMMENT_BODY TRUE
J 0
(2625 1175);
DISPLAY 0.872340 (2625 1175);
PAINT GREEN (2625 1175);
DISPLAY INVISIBLE (2625 1175);
FORCEPROP 1 LAST OFFPAGE TRUE
J 0
(2825 1150);
DISPLAY 0.872340 (2825 1150);
PAINT AQUA (2825 1150);
DISPLAY INVISIBLE (2825 1150);
FORCEPROP 2 LAST PATH I89
J 0
(2550 1350);
DISPLAY 1.021277 (2550 1350);
DISPLAY INVISIBLE (2550 1350);
FORCEADD OFFPAGE..1
(2500 1875);
FORCEPROP 2 LAST $XR0 177 
J 0
(2248 1875);
DISPLAY 0.638298 (2248 1875);
PAINT MONO (2248 1875);
FORCEPROP 2 LAST PATH I9
J 0
(2550 1950);
DISPLAY 1.021277 (2550 1950);
DISPLAY INVISIBLE (2550 1950);
FORCEPROP 2 LAST CDS_LIB standard
J 0
(2500 1875);
DISPLAY INVISIBLE (2500 1875);
FORCEPROP 1 LAST COMMENT_BODY TRUE
J 0
(2625 1775);
DISPLAY 0.872340 (2625 1775);
PAINT GREEN (2625 1775);
DISPLAY INVISIBLE (2625 1775);
FORCEPROP 1 LAST OFFPAGE TRUE
J 0
(2825 1750);
DISPLAY 0.872340 (2825 1750);
PAINT AQUA (2825 1750);
DISPLAY INVISIBLE (2825 1750);
FORCEADD OFFPAGE..1
(2500 1125);
FORCEPROP 2 LAST $XR0 177 
J 0
(2248 1125);
DISPLAY 0.638298 (2248 1125);
PAINT MONO (2248 1125);
FORCEPROP 1 LAST OFFPAGE TRUE
J 0
(2825 1000);
DISPLAY 0.872340 (2825 1000);
PAINT AQUA (2825 1000);
DISPLAY INVISIBLE (2825 1000);
FORCEPROP 1 LAST COMMENT_BODY TRUE
J 0
(2625 1025);
DISPLAY 0.872340 (2625 1025);
PAINT GREEN (2625 1025);
DISPLAY INVISIBLE (2625 1025);
FORCEPROP 2 LAST CDS_LIB standard
J 0
(2500 1125);
DISPLAY INVISIBLE (2500 1125);
FORCEPROP 2 LAST PATH I90
J 0
(2550 1200);
DISPLAY 1.021277 (2550 1200);
DISPLAY INVISIBLE (2550 1200);
FORCEADD OFFPAGE..1
(2500 1175);
FORCEPROP 2 LAST $XR0 177 
J 0
(2248 1175);
DISPLAY 0.638298 (2248 1175);
PAINT MONO (2248 1175);
FORCEPROP 1 LAST OFFPAGE TRUE
J 0
(2825 1050);
DISPLAY 0.872340 (2825 1050);
PAINT AQUA (2825 1050);
DISPLAY INVISIBLE (2825 1050);
FORCEPROP 1 LAST COMMENT_BODY TRUE
J 0
(2625 1075);
DISPLAY 0.872340 (2625 1075);
PAINT GREEN (2625 1075);
DISPLAY INVISIBLE (2625 1075);
FORCEPROP 2 LAST CDS_LIB standard
J 0
(2500 1175);
DISPLAY INVISIBLE (2500 1175);
FORCEPROP 2 LAST PATH I91
J 0
(2550 1250);
DISPLAY 1.021277 (2550 1250);
DISPLAY INVISIBLE (2550 1250);
FORCEADD UNIVERSAL_GND..1
(3575 -175);
FORCEPROP 3 LASTPIN (3575 -125) SIG_NAME GND\g
J 0
(3585 -115);
DISPLAY 0.659574 (3585 -115);
PAINT MONO (3585 -115);
DISPLAY INVISIBLE (3585 -115);
FORCEPROP 1 LAST HDL_POWER GND
J 1
(3600 -250);
DISPLAY 0.872340 (3600 -250);
PAINT GREEN (3600 -250);
DISPLAY INVISIBLE (3600 -250);
FORCEPROP 1 LAST PATH I92
J 0
(3650 -175);
DISPLAY 0.872340 (3650 -175);
PAINT AQUA (3650 -175);
DISPLAY INVISIBLE (3650 -175);
FORCEPROP 2 LAST CDS_LIB logical_power
J 0
(3575 -175);
DISPLAY INVISIBLE (3575 -175);
FORCEADD UNIVERSAL_GND..1
(-1125 -125);
FORCEPROP 3 LASTPIN (-1125 -75) SIG_NAME GND\g
J 0
(-1115 -65);
DISPLAY 0.659574 (-1115 -65);
PAINT MONO (-1115 -65);
DISPLAY INVISIBLE (-1115 -65);
FORCEPROP 1 LAST PATH I93
J 0
(-1050 -125);
DISPLAY 0.872340 (-1050 -125);
PAINT AQUA (-1050 -125);
DISPLAY INVISIBLE (-1050 -125);
FORCEPROP 2 LAST CDS_LIB logical_power
J 0
(-1125 -125);
DISPLAY INVISIBLE (-1125 -125);
FORCEPROP 1 LAST HDL_POWER GND
J 1
(-1100 -200);
DISPLAY 0.872340 (-1100 -200);
PAINT GREEN (-1100 -200);
DISPLAY INVISIBLE (-1100 -200);
FORCEADD QUANTA_TITLE_BLOCK_C..1
(5650 -1650);
FORCEPROP 0 LAST CDS_CON_LAST_MODIFIED Fri Aug 25 14:02:03 2023
J 0
(3765 -1635);
PAINT MONO (3765 -1635);
DISPLAY INVISIBLE (3765 -1635);
FORCEPROP 1 LAST CUSTOM_TXT_CDS <CON_LAST_MODIFIED>
J 0
(3765 -1635);
DISPLAY 0.978723 (3765 -1635);
FORCEPROP 2 LAST CUSTOM_TXT_CDS <XR_PAGE_TITLE>
J 0
(-2240 3600);
DISPLAY 0.638298 (-2240 3600);
PAINT PINK (-2240 3600);
DISPLAY INVISIBLE (-2240 3600);
FORCEPROP 2 LAST CUSTOM_TXT_CDS <Q_NUMBER>
J 0
(4247 -1547);
DISPLAY 1.212766 (4247 -1547);
FORCEPROP 2 LAST CUSTOM_TXT_CDS <CON_PAGE_NUM> OF <CON_TOTAL_PAGES>
J 0
(5204 -1632);
DISPLAY 0.978723 (5204 -1632);
FORCEPROP 2 LAST CUSTOM_TXT_CDS <NAME_1>
J 0
(2475 -1475);
FORCEPROP 2 LAST CUSTOM_TXT_CDS <NAME_2>
J 0
(2475 -1600);
FORCEPROP 2 LAST CUSTOM_TXT_CDS <Q_PROJ>
J 0
(3268 -1548);
DISPLAY 1.212766 (3268 -1548);
FORCEPROP 2 LAST CUSTOM_TXT_CDS <Q_REV>
J 0
(5466 -1547);
DISPLAY 1.212766 (5466 -1547);
FORCEPROP 1 LAST Q_TITLE PCIE - CPU1_EXAMAX_P0/P4_X16
J 0
(-3650 -1600);
DISPLAY 1.957447 (-3650 -1600);
PAINT GREEN (-3650 -1600);
FORCEPROP 1 LAST Q_DEPT 
J 1
(1887 -1601);
DISPLAY 1.957447 (1887 -1601);
PAINT GREEN (1887 -1601);
FORCEPROP 2 LAST CDS_XR_PAGE_TITLE CR-142 : @S9S_MB_2U_LIB.S9S_MB_2U(SCH_1):PAGE142
J 0
(-2240 3600);
DISPLAY 0.638298 (-2240 3600);
PAINT PINK (-2240 3600);
DISPLAY INVISIBLE (-2240 3600);
FORCEPROP 1 LAST COMMENT_BODY TRUE
J 0
(5662 -1663);
DISPLAY 0.978723 (5662 -1663);
PAINT GREEN (5662 -1663);
DISPLAY INVISIBLE (5662 -1663);
FORCEPROP 2 LAST PAGE_BORDER TRUE
J 0
(-2240 3600);
DISPLAY 0.638298 (-2240 3600);
PAINT PINK (-2240 3600);
DISPLAY INVISIBLE (-2240 3600);
FORCEPROP 1 LAST CDS_LMAN_SYM_OUTLINE -9475,6775,100,-125
J 0
(5650 -1650);
DISPLAY 0.468085 (5650 -1650);
PAINT GREEN (5650 -1650);
DISPLAY INVISIBLE (5650 -1650);
FORCEPROP 2 LAST CDS_LIB pure_quanta
J 0
(5650 -1650);
PAINT MONO (5650 -1650);
DISPLAY INVISIBLE (5650 -1650);
WIRE 16 -1 (-1125 225)(-1125 -75);
WIRE 16 -1 (-1125 375)(-1125 225);
WIRE 16 -1 (-950 225)(-1125 225);
WIRE 16 -1 (3575 225)(3575 -125);
WIRE 16 -1 (3575 375)(3575 225);
WIRE 16 -1 (3800 225)(3575 225);
WIRE 16 -1 (3800 575)(2550 575);
FORCEPROP 2 LAST SIG_NAME P5E_CPU1_PE4_RX_DP<8>
J 0
(2690 585);
DISPLAY 0.638298 (2690 585);
WIRE 16 -1 (-950 1325)(-2175 1325);
FORCEPROP 2 LAST SIG_NAME P5E_CPU1_PE0_TX_C_DN<2>
J 0
(-2035 1335);
DISPLAY 0.638298 (-2035 1335);
WIRE 16 -1 (-950 1425)(-2175 1425);
FORCEPROP 2 LAST SIG_NAME P5E_CPU1_PE4_RX_DN<13>
J 0
(-2035 1435);
DISPLAY 0.638298 (-2035 1435);
WIRE 16 -1 (-950 1575)(-2175 1575);
FORCEPROP 2 LAST SIG_NAME P5E_CPU1_PE0_RX_DP<2>
J 0
(-2035 1585);
DISPLAY 0.638298 (-2035 1585);
WIRE 16 -1 (-950 1625)(-2175 1625);
FORCEPROP 2 LAST SIG_NAME P5E_CPU1_PE0_RX_DN<2>
J 0
(-2035 1635);
DISPLAY 0.638298 (-2035 1635);
WIRE 16 -1 (-950 375)(-1125 375);
WIRE 16 -1 (-1125 525)(-1125 375);
WIRE 16 -1 (-950 525)(-1125 525);
WIRE 16 -1 (-1125 525)(-1125 675);
WIRE 16 -1 (-950 675)(-1125 675);
WIRE 16 -1 (-1125 675)(-1125 825);
WIRE 16 -1 (-950 825)(-1125 825);
WIRE 16 -1 (-1125 1075)(-1125 825);
WIRE 16 -1 (-950 1075)(-1125 1075);
WIRE 16 -1 (-1125 1225)(-1125 1075);
WIRE 16 -1 (-950 1225)(-1125 1225);
WIRE 16 -1 (-1125 1375)(-1125 1225);
WIRE 16 -1 (-950 1375)(-1125 1375);
WIRE 16 -1 (-1125 1525)(-1125 1375);
WIRE 16 -1 (-950 1525)(-1125 1525);
WIRE 16 -1 (-1125 1675)(-1125 1525);
WIRE 16 -1 (-950 1675)(-1125 1675);
WIRE 16 -1 (-1125 1825)(-1125 1675);
WIRE 16 -1 (-950 1825)(-1125 1825);
WIRE 16 -1 (-1125 1975)(-1125 1825);
WIRE 16 -1 (-950 1975)(-1125 1975);
WIRE 16 -1 (-1125 2125)(-1125 1975);
WIRE 16 -1 (-950 2125)(-1125 2125);
WIRE 16 -1 (-1125 2275)(-1125 2125);
WIRE 16 -1 (-950 2275)(-1125 2275);
WIRE 16 -1 (-1125 2425)(-1125 2275);
WIRE 16 -1 (-950 2425)(-1125 2425);
WIRE 16 -1 (-1125 2675)(-1125 2425);
WIRE 16 -1 (-950 2675)(-1125 2675);
WIRE 16 -1 (-1125 2825)(-1125 2675);
WIRE 16 -1 (-950 2825)(-1125 2825);
WIRE 16 -1 (-1125 2975)(-1125 2825);
WIRE 16 -1 (-950 2975)(-1125 2975);
WIRE 16 -1 (-1125 3125)(-1125 2975);
WIRE 16 -1 (-950 3125)(-1125 3125);
WIRE 16 -1 (-1125 3275)(-1125 3125);
WIRE 16 -1 (-950 3275)(-1125 3275);
WIRE 16 -1 (-950 2725)(-2175 2725);
FORCEPROP 2 LAST SIG_NAME P5E_CPU1_PE4_TX_C_DP<15>
J 0
(-2035 2735);
DISPLAY 0.638298 (-2035 2735);
WIRE 16 -1 (-950 2875)(-2175 2875);
FORCEPROP 2 LAST SIG_NAME P5E_CPU1_PE0_TX_C_DP<0>
J 0
(-2035 2885);
DISPLAY 0.638298 (-2035 2885);
WIRE 16 -1 (-950 2025)(-2175 2025);
FORCEPROP 2 LAST SIG_NAME P5E_CPU1_PE0_TX_C_DP<1>
J 0
(-2035 2035);
DISPLAY 0.638298 (-2035 2035);
WIRE 16 -1 (-950 2175)(-2175 2175);
FORCEPROP 2 LAST SIG_NAME P5E_CPU1_PE4_RX_DP<14>
J 0
(-2035 2185);
DISPLAY 0.638298 (-2035 2185);
WIRE 16 -1 (-950 2225)(-2175 2225);
FORCEPROP 2 LAST SIG_NAME P5E_CPU1_PE4_RX_DN<14>
J 0
(-2035 2235);
DISPLAY 0.638298 (-2035 2235);
WIRE 16 -1 (-950 2325)(-2175 2325);
FORCEPROP 2 LAST SIG_NAME P5E_CPU1_PE0_RX_DN<1>
J 0
(-2035 2335);
DISPLAY 0.638298 (-2035 2335);
WIRE 16 -1 (3800 2175)(2550 2175);
FORCEPROP 2 LAST SIG_NAME P5E_CPU1_PE4_RX_DP<10>
J 0
(2690 2185);
DISPLAY 0.638298 (2690 2185);
WIRE 16 -1 (3800 2225)(2550 2225);
FORCEPROP 2 LAST SIG_NAME P5E_CPU1_PE4_RX_DN<10>
J 0
(2690 2235);
DISPLAY 0.638298 (2690 2235);
WIRE 16 -1 (3800 3075)(2550 3075);
FORCEPROP 2 LAST SIG_NAME P5E_CPU1_PE4_RX_DP<11>
J 0
(2690 3085);
DISPLAY 0.638298 (2690 3085);
WIRE 16 -1 (3800 3025)(2550 3025);
FORCEPROP 2 LAST SIG_NAME P5E_CPU1_PE4_RX_DN<11>
J 0
(2690 3035);
DISPLAY 0.638298 (2690 3035);
WIRE 16 -1 (3800 2925)(2550 2925);
FORCEPROP 2 LAST SIG_NAME P5E_CPU1_PE0_TX_C_DN<4>
J 0
(2690 2935);
DISPLAY 0.638298 (2690 2935);
WIRE 16 -1 (3800 2875)(2550 2875);
FORCEPROP 2 LAST SIG_NAME P5E_CPU1_PE0_TX_C_DP<4>
J 0
(2690 2885);
DISPLAY 0.638298 (2690 2885);
WIRE 16 -1 (3800 2725)(2550 2725);
FORCEPROP 2 LAST SIG_NAME P5E_CPU1_PE4_TX_C_DN<11>
J 0
(2690 2735);
DISPLAY 0.638298 (2690 2735);
WIRE 16 -1 (3800 2775)(2550 2775);
FORCEPROP 2 LAST SIG_NAME P5E_CPU1_PE4_TX_C_DP<11>
J 0
(2690 2785);
DISPLAY 0.638298 (2690 2785);
WIRE 16 -1 (3800 2625)(2550 2625);
FORCEPROP 2 LAST SIG_NAME FM_GPU_PWR_EN_R_BUF
J 0
(2690 2635);
DISPLAY 0.638298 (2690 2635);
WIRE 16 -1 (2550 2475)(3800 2475);
FORCEPROP 2 LAST SIG_NAME GPU_BASE_ID0
J 0
(2690 2485);
DISPLAY 0.638298 (2690 2485);
WIRE 16 -1 (3800 2375)(2550 2375);
FORCEPROP 2 LAST SIG_NAME P5E_CPU1_PE0_RX_DN<5>
J 0
(2690 2385);
DISPLAY 0.638298 (2690 2385);
WIRE 16 -1 (3800 2325)(2550 2325);
FORCEPROP 2 LAST SIG_NAME P5E_CPU1_PE0_RX_DP<5>
J 0
(2690 2335);
DISPLAY 0.638298 (2690 2335);
WIRE 16 -1 (3800 375)(3575 375);
WIRE 16 -1 (3575 525)(3575 375);
WIRE 16 -1 (3800 525)(3575 525);
WIRE 16 -1 (3575 675)(3575 525);
WIRE 16 -1 (3800 675)(3575 675);
WIRE 16 -1 (3575 825)(3575 675);
WIRE 16 -1 (3800 825)(3575 825);
WIRE 16 -1 (3575 1075)(3575 825);
WIRE 16 -1 (3800 1075)(3575 1075);
WIRE 16 -1 (3575 1225)(3575 1075);
WIRE 16 -1 (3800 1225)(3575 1225);
WIRE 16 -1 (3575 1375)(3575 1225);
WIRE 16 -1 (3800 1375)(3575 1375);
WIRE 16 -1 (3575 1525)(3575 1375);
WIRE 16 -1 (3800 1525)(3575 1525);
WIRE 16 -1 (3575 1675)(3575 1525);
WIRE 16 -1 (3800 1675)(3575 1675);
WIRE 16 -1 (3575 1825)(3575 1675);
WIRE 16 -1 (3800 1825)(3575 1825);
WIRE 16 -1 (3575 1975)(3575 1825);
WIRE 16 -1 (3800 1975)(3575 1975);
WIRE 16 -1 (3575 2125)(3575 1975);
WIRE 16 -1 (3800 2125)(3575 2125);
WIRE 16 -1 (3575 2275)(3575 2125);
WIRE 16 -1 (3800 2275)(3575 2275);
WIRE 16 -1 (3575 2425)(3575 2275);
WIRE 16 -1 (3800 2425)(3575 2425);
WIRE 16 -1 (3575 2675)(3575 2425);
WIRE 16 -1 (3800 2675)(3575 2675);
WIRE 16 -1 (3575 2825)(3575 2675);
WIRE 16 -1 (3800 2825)(3575 2825);
WIRE 16 -1 (3575 2975)(3575 2825);
WIRE 16 -1 (3800 2975)(3575 2975);
WIRE 16 -1 (3575 3125)(3575 2975);
WIRE 16 -1 (3800 3125)(3575 3125);
WIRE 16 -1 (3575 3275)(3575 3125);
WIRE 16 -1 (3800 3275)(3575 3275);
WIRE 16 -1 (3800 2075)(2550 2075);
FORCEPROP 2 LAST SIG_NAME P5E_CPU1_PE0_TX_C_DN<5>
J 0
(2690 2085);
DISPLAY 0.638298 (2690 2085);
WIRE 16 -1 (3800 2025)(2550 2025);
FORCEPROP 2 LAST SIG_NAME P5E_CPU1_PE0_TX_C_DP<5>
J 0
(2690 2035);
DISPLAY 0.638298 (2690 2035);
WIRE 16 -1 (3800 1925)(2550 1925);
FORCEPROP 2 LAST SIG_NAME P5E_CPU1_PE4_TX_C_DN<10>
J 0
(2690 1935);
DISPLAY 0.638298 (2690 1935);
WIRE 16 -1 (3800 1875)(2550 1875);
FORCEPROP 2 LAST SIG_NAME P5E_CPU1_PE4_TX_C_DP<10>
J 0
(2690 1885);
DISPLAY 0.638298 (2690 1885);
WIRE 16 -1 (3800 1625)(2550 1625);
FORCEPROP 2 LAST SIG_NAME P5E_CPU1_PE0_RX_DN<6>
J 0
(2690 1635);
DISPLAY 0.638298 (2690 1635);
WIRE 16 -1 (3800 1575)(2550 1575);
FORCEPROP 2 LAST SIG_NAME P5E_CPU1_PE0_RX_DP<6>
J 0
(2690 1585);
DISPLAY 0.638298 (2690 1585);
WIRE 16 -1 (3800 1475)(2550 1475);
FORCEPROP 2 LAST SIG_NAME P5E_CPU1_PE4_RX_DP<9>
J 0
(2690 1485);
DISPLAY 0.638298 (2690 1485);
WIRE 16 -1 (3800 1425)(2550 1425);
FORCEPROP 2 LAST SIG_NAME P5E_CPU1_PE4_RX_DN<9>
J 0
(2690 1435);
DISPLAY 0.638298 (2690 1435);
WIRE 16 -1 (3800 1325)(2550 1325);
FORCEPROP 2 LAST SIG_NAME P5E_CPU1_PE0_TX_C_DN<6>
J 0
(2690 1335);
DISPLAY 0.638298 (2690 1335);
WIRE 16 -1 (3800 725)(2550 725);
FORCEPROP 2 LAST SIG_NAME P5E_CPU1_PE0_RX_DP<7>
J 0
(2690 735);
DISPLAY 0.638298 (2690 735);
WIRE 16 -1 (3800 625)(2550 625);
FORCEPROP 2 LAST SIG_NAME P5E_CPU1_PE4_RX_DN<8>
J 0
(2690 635);
DISPLAY 0.638298 (2690 635);
WIRE 16 -1 (3800 775)(2550 775);
FORCEPROP 2 LAST SIG_NAME P5E_CPU1_PE0_RX_DN<7>
J 0
(2690 785);
DISPLAY 0.638298 (2690 785);
WIRE 16 -1 (3800 875)(2525 875);
FORCEPROP 2 LAST SIG_NAME GPU_PEX_STRAP1
J 0
(2690 885);
DISPLAY 0.638298 (2690 885);
WIRE 16 -1 (3800 1025)(2550 1025);
FORCEPROP 2 LAST SIG_NAME GPU_PRSNT_N
J 0
(2690 1035);
DISPLAY 0.638298 (2690 1035);
WIRE 16 -1 (3800 1125)(2550 1125);
FORCEPROP 2 LAST SIG_NAME P5E_CPU1_PE4_TX_C_DP<9>
J 0
(2690 1135);
DISPLAY 0.638298 (2690 1135);
WIRE 16 -1 (3800 1175)(2550 1175);
FORCEPROP 2 LAST SIG_NAME P5E_CPU1_PE4_TX_C_DN<9>
J 0
(2690 1185);
DISPLAY 0.638298 (2690 1185);
WIRE 16 -1 (-950 2375)(-2175 2375);
FORCEPROP 2 LAST SIG_NAME P5E_CPU1_PE0_RX_DP<1>
J 0
(-2035 2385);
DISPLAY 0.638298 (-2035 2385);
WIRE 16 -1 (-950 2475)(-2175 2475);
FORCEPROP 2 LAST SIG_NAME GPU_FPGA_RST_R_BUF_N
J 0
(-2035 2485);
DISPLAY 0.638298 (-2035 2485);
WIRE 16 -1 (-2175 2625)(-950 2625);
FORCEPROP 2 LAST SIG_NAME GPU_BASE_ID1
J 0
(-2035 2635);
DISPLAY 0.638298 (-2035 2635);
WIRE 16 -1 (-950 2775)(-2175 2775);
FORCEPROP 2 LAST SIG_NAME P5E_CPU1_PE4_TX_C_DN<15>
J 0
(-2035 2785);
DISPLAY 0.638298 (-2035 2785);
WIRE 16 -1 (-950 2925)(-2175 2925);
FORCEPROP 2 LAST SIG_NAME P5E_CPU1_PE0_TX_C_DN<0>
J 0
(-2035 2935);
DISPLAY 0.638298 (-2035 2935);
WIRE 16 -1 (-950 3025)(-2175 3025);
FORCEPROP 2 LAST SIG_NAME P5E_CPU1_PE4_RX_DN<15>
J 0
(-2035 3035);
DISPLAY 0.638298 (-2035 3035);
WIRE 16 -1 (3800 3175)(2550 3175);
FORCEPROP 2 LAST SIG_NAME P5E_CPU1_PE0_RX_DP<4>
J 0
(2690 3185);
DISPLAY 0.638298 (2690 3185);
WIRE 16 -1 (3800 1275)(2550 1275);
FORCEPROP 2 LAST SIG_NAME P5E_CPU1_PE0_TX_C_DP<6>
J 0
(2690 1285);
DISPLAY 0.638298 (2690 1285);
WIRE 16 -1 (-950 2075)(-2175 2075);
FORCEPROP 2 LAST SIG_NAME P5E_CPU1_PE0_TX_C_DN<1>
J 0
(-2035 2085);
DISPLAY 0.638298 (-2035 2085);
WIRE 16 -1 (-950 1925)(-2175 1925);
FORCEPROP 2 LAST SIG_NAME P5E_CPU1_PE4_TX_C_DN<14>
J 0
(-2035 1935);
DISPLAY 0.638298 (-2035 1935);
WIRE 16 -1 (-950 1875)(-2175 1875);
FORCEPROP 2 LAST SIG_NAME P5E_CPU1_PE4_TX_C_DP<14>
J 0
(-2035 1885);
DISPLAY 0.638298 (-2035 1885);
WIRE 16 -1 (-950 3225)(-2175 3225);
FORCEPROP 2 LAST SIG_NAME P5E_CPU1_PE0_RX_DN<0>
J 0
(-2035 3235);
DISPLAY 0.638298 (-2035 3235);
WIRE 16 -1 (-950 3175)(-2175 3175);
FORCEPROP 2 LAST SIG_NAME P5E_CPU1_PE0_RX_DP<0>
J 0
(-2035 3185);
DISPLAY 0.638298 (-2035 3185);
WIRE 16 -1 (-950 775)(-2175 775);
FORCEPROP 2 LAST SIG_NAME P5E_CPU1_PE0_RX_DP<3>
J 0
(-2035 785);
DISPLAY 0.638298 (-2035 785);
WIRE 16 -1 (-950 1125)(-2175 1125);
FORCEPROP 2 LAST SIG_NAME P5E_CPU1_PE4_TX_C_DP<13>
J 0
(-2035 1135);
DISPLAY 0.638298 (-2035 1135);
WIRE 16 -1 (-950 1175)(-2175 1175);
FORCEPROP 2 LAST SIG_NAME P5E_CPU1_PE4_TX_C_DN<13>
J 0
(-2035 1185);
DISPLAY 0.638298 (-2035 1185);
WIRE 16 -1 (-950 1275)(-2175 1275);
FORCEPROP 2 LAST SIG_NAME P5E_CPU1_PE0_TX_C_DP<2>
J 0
(-2035 1285);
DISPLAY 0.638298 (-2035 1285);
WIRE 16 -1 (-950 1475)(-2175 1475);
FORCEPROP 2 LAST SIG_NAME P5E_CPU1_PE4_RX_DP<13>
J 0
(-2035 1485);
DISPLAY 0.638298 (-2035 1485);
WIRE 16 -1 (-950 3075)(-2175 3075);
FORCEPROP 2 LAST SIG_NAME P5E_CPU1_PE4_RX_DP<15>
J 0
(-2035 3085);
DISPLAY 0.638298 (-2035 3085);
WIRE 16 -1 (-950 1025)(-2175 1025);
FORCEPROP 2 LAST SIG_NAME FM_GPU_PWRGD
J 0
(-2035 1035);
DISPLAY 0.638298 (-2035 1035);
WIRE 16 -1 (-2200 875)(-950 875);
FORCEPROP 2 LAST SIG_NAME GPU_PEX_STRAP0
J 0
(-2035 885);
DISPLAY 0.638298 (-2035 885);
WIRE 16 -1 (-950 725)(-2175 725);
FORCEPROP 2 LAST SIG_NAME P5E_CPU1_PE0_RX_DN<3>
J 0
(-2035 735);
DISPLAY 0.638298 (-2035 735);
WIRE 16 -1 (-950 625)(-2175 625);
FORCEPROP 2 LAST SIG_NAME P5E_CPU1_PE4_RX_DN<12>
J 0
(-2035 635);
DISPLAY 0.638298 (-2035 635);
WIRE 16 -1 (-950 425)(-2175 425);
FORCEPROP 2 LAST SIG_NAME P5E_CPU1_PE0_TX_C_DP<3>
J 0
(-2035 435);
DISPLAY 0.638298 (-2035 435);
WIRE 16 -1 (-950 575)(-2175 575);
FORCEPROP 2 LAST SIG_NAME P5E_CPU1_PE4_RX_DP<12>
J 0
(-2035 585);
DISPLAY 0.638298 (-2035 585);
WIRE 16 -1 (3800 425)(2550 425);
FORCEPROP 2 LAST SIG_NAME P5E_CPU1_PE0_TX_C_DP<7>
J 0
(2690 435);
DISPLAY 0.638298 (2690 435);
WIRE 16 -1 (3800 475)(2550 475);
FORCEPROP 2 LAST SIG_NAME P5E_CPU1_PE0_TX_C_DN<7>
J 0
(2690 485);
DISPLAY 0.638298 (2690 485);
WIRE 16 -1 (3800 325)(2550 325);
FORCEPROP 2 LAST SIG_NAME P5E_CPU1_PE4_TX_C_DN<8>
J 0
(2690 335);
DISPLAY 0.638298 (2690 335);
WIRE 16 -1 (3800 275)(2550 275);
FORCEPROP 2 LAST SIG_NAME P5E_CPU1_PE4_TX_C_DP<8>
J 0
(2690 285);
DISPLAY 0.638298 (2690 285);
WIRE 16 -1 (3800 3225)(2550 3225);
FORCEPROP 2 LAST SIG_NAME P5E_CPU1_PE0_RX_DN<4>
J 0
(2690 3235);
DISPLAY 0.638298 (2690 3235);
WIRE 16 -1 (-950 475)(-2175 475);
FORCEPROP 2 LAST SIG_NAME P5E_CPU1_PE0_TX_C_DN<3>
J 0
(-2035 485);
DISPLAY 0.638298 (-2035 485);
WIRE 16 -1 (-950 325)(-2175 325);
FORCEPROP 2 LAST SIG_NAME P5E_CPU1_PE4_TX_C_DN<12>
J 0
(-2035 335);
DISPLAY 0.638298 (-2035 335);
WIRE 16 -1 (-950 275)(-2175 275);
FORCEPROP 2 LAST SIG_NAME P5E_CPU1_PE4_TX_C_DP<12>
J 0
(-2035 285);
DISPLAY 0.638298 (-2035 285);
DOT 1 (-1125 1975);
DOT 1 (3575 2275);
DOT 1 (3575 2125);
DOT 1 (3575 1975);
DOT 1 (3575 1825);
DOT 1 (3575 1075);
DOT 1 (3575 2675);
DOT 1 (3575 2425);
DOT 1 (-1125 2675);
DOT 1 (-1125 825);
DOT 1 (-1125 225);
DOT 1 (-1125 375);
DOT 1 (-1125 525);
DOT 1 (-1125 675);
DOT 1 (-1125 1225);
DOT 1 (-1125 1075);
DOT 1 (-1125 1375);
DOT 1 (-1125 1525);
DOT 1 (-1125 2125);
DOT 1 (-1125 2275);
DOT 1 (-1125 2425);
DOT 1 (-1125 2825);
DOT 1 (-1125 2975);
DOT 1 (-1125 3125);
DOT 1 (3575 3125);
DOT 1 (3575 2975);
DOT 1 (3575 2825);
DOT 1 (3575 1675);
DOT 1 (3575 1375);
DOT 1 (3575 1525);
DOT 1 (3575 1225);
DOT 1 (3575 375);
DOT 1 (3575 225);
DOT 1 (3575 525);
DOT 1 (3575 675);
DOT 1 (3575 825);
DOT 1 (-1125 1825);
DOT 1 (-1125 1675);
FORCENOTE
DP/DN SWAP
(1650 3050) 0;
DISPLAY LEFT (1650 3050);
DISPLAY 1.021277 (1650 3050);
FORCENOTE
DP/DN SWAP
(1650 725) 0;
DISPLAY LEFT (1650 725);
DISPLAY 1.021277 (1650 725);
FORCENOTE
DP/DN SWAP
(1650 1450) 0;
DISPLAY LEFT (1650 1450);
DISPLAY 1.021277 (1650 1450);
FORCENOTE
DP/DN SWAP
(1650 2725) 0;
DISPLAY LEFT (1650 2725);
DISPLAY 1.021277 (1650 2725);
FORCENOTE
DP/DN SWAP
(-3000 3025) 0;
DISPLAY LEFT (-3000 3025);
DISPLAY 1.021277 (-3000 3025);
FORCENOTE
DP/DN SWAP
(-3000 2325) 0;
DISPLAY LEFT (-3000 2325);
DISPLAY 1.021277 (-3000 2325);
FORCENOTE
DP/DN SWAP
(-2975 725) 0;
DISPLAY LEFT (-2975 725);
DISPLAY 1.021277 (-2975 725);
FORCENOTE
DP/DN SWAP
(-3000 1450) 0;
DISPLAY LEFT (-3000 1450);
DISPLAY 1.021277 (-3000 1450);
FORCENOTE
CPU1_PE4_TX/RX<0-15> LANE REVERSAL
(-3500 3700) 0;
DISPLAY LEFT (-3500 3700);
DISPLAY 1.276596 (-3500 3700);
PAINT WHITE (-3500 3700);
FORCENOTE
20210527 MODIFY FOR GT
(-3525 4700) 0;
DISPLAY LEFT (-3525 4700);
DISPLAY 2.510638 (-3525 4700);
PAINT PINK (-3525 4700);
QUIT
